G04 ================== begin FILE IDENTIFICATION RECORD ==================*
G04 Layout Name:  9052_F0T_PDB_Converter_Brick_F_V03_1208_1600.brd*
G04 Film Name:    gnd1*
G04 File Format:  Gerber RS274X*
G04 File Origin:  Cadence Allegro 17.2-S081*
G04 Origin Date:  Wed Dec 21 09:54:59 2022*
G04 *
G04 Layer:  DRAWING FORMAT/TITLE_BLOCK_A*
G04 Layer:  PIN/SPECIAL_DRILL*
G04 Layer:  VIA CLASS/GND1*
G04 Layer:  PIN/GND1*
G04 Layer:  MANUFACTURING/PHOTOPLOT_OUTLINE*
G04 Layer:  ETCH/GND1*
G04 Layer:  DRAWING FORMAT/TITLE_BLOCK*
G04 Layer:  DRAWING FORMAT/TITLE_DATA_GND1*
G04 *
G04 Offset:    (0.00 0.00)*
G04 Mirror:    No*
G04 Mode:      Negative*
G04 Rotation:  0*
G04 FullContactRelief:  No*
G04 UndefLineWidth:     6.00*
G04 ================== end FILE IDENTIFICATION RECORD ====================*
%FSLAX25Y25*MOIN*%
%IR0*IPPOS*OFA0.00000B0.00000*MIA0B0*SFA1.00000B1.00000*%
%ADD20C,.03*%
%AMMACRO12*
4,1,41,.45275,-.05906,
.463006,-.058163,
.47295,-.055498,
.48228,-.051147,
.490713,-.045243,
.497993,-.037963,
.503897,-.02953,
.508248,-.0202,
.510913,-.010256,
.51181,0.0,
.510913,.010256,
.508248,.0202,
.503897,.02953,
.497993,.037963,
.490713,.045243,
.48228,.051147,
.47295,.055498,
.463006,.058163,
.45275,.05906,
.33464,.05906,
-.4082,.09829,
-.425347,.097699,
-.442131,.09414,
-.458041,.08772,
-.472595,.078635,
-.485351,.06716,
-.49592,.053645,
-.503981,.0385,
-.509291,.022185,
-.511686,.005196,
-.511095,-.011951,
-.507536,-.028734,
-.501116,-.044645,
-.492031,-.059199,
-.480557,-.071954,
-.467041,-.082523,
-.451896,-.090585,
-.435582,-.095894,
-.418593,-.09829,
-.4082,-.09829,
.33464,-.05906,
.45275,-.05906,
0.0*
%
%ADD12MACRO12*%
%ADD35C,.06*%
%ADD16C,.061*%
%ADD28C,.062*%
%ADD25C,.026*%
%ADD17C,.054*%
%AMMACRO27*
4,1,36,.0025,0.0,
.002462,.000434,
.002349,.000855,
.002165,.00125,
.001915,.001607,
.001607,.001915,
.00125,.002165,
.000855,.002349,
.000434,.002462,
0.0,.0025,
-.000434,.002462,
-.000855,.002349,
-.00125,.002165,
-.001607,.001915,
-.001915,.001607,
-.002165,.00125,
-.002349,.000855,
-.002462,.000434,
-.0025,0.0,
-.002462,-.000434,
-.002349,-.000855,
-.002165,-.00125,
-.001915,-.001607,
-.001607,-.001915,
-.00125,-.002165,
-.000855,-.002349,
-.000434,-.002462,
0.0,-.0025,
.000434,-.002462,
.000855,-.002349,
.00125,-.002165,
.001607,-.001915,
.001915,-.001607,
.002165,-.00125,
.002349,-.000855,
.002462,-.000434,
.0025,0.0,
180.*
%
%ADD27MACRO27*%
%AMMACRO23*
4,1,36,.0025,0.0,
.002462,.000434,
.002349,.000855,
.002165,.00125,
.001915,.001607,
.001607,.001915,
.00125,.002165,
.000855,.002349,
.000434,.002462,
0.0,.0025,
-.000434,.002462,
-.000855,.002349,
-.00125,.002165,
-.001607,.001915,
-.001915,.001607,
-.002165,.00125,
-.002349,.000855,
-.002462,.000434,
-.0025,0.0,
-.002462,-.000434,
-.002349,-.000855,
-.002165,-.00125,
-.001915,-.001607,
-.001607,-.001915,
-.00125,-.002165,
-.000855,-.002349,
-.000434,-.002462,
0.0,-.0025,
.000434,-.002462,
.000855,-.002349,
.00125,-.002165,
.001607,-.001915,
.001915,-.001607,
.002165,-.00125,
.002349,-.000855,
.002462,-.000434,
.0025,0.0,
270.*
%
%ADD23MACRO23*%
%ADD33C,.083*%
%ADD30C,.056*%
%ADD43C,.066*%
%ADD38C,.06015*%
%ADD40C,.087*%
%AMMACRO37*
4,1,36,0.0,.019,
-.003299,.018711,
-.006498,.017854,
-.0095,.016454,
-.012213,.014555,
-.014555,.012213,
-.016454,.0095,
-.017854,.006498,
-.018711,.003299,
-.019,0.0,
-.018711,-.003299,
-.017854,-.006498,
-.016454,-.0095,
-.014555,-.012213,
-.012213,-.014555,
-.0095,-.016454,
-.006498,-.017854,
-.003299,-.018711,
0.0,-.019,
.003299,-.018711,
.006498,-.017854,
.0095,-.016454,
.012213,-.014555,
.014555,-.012213,
.016454,-.0095,
.017854,-.006498,
.018711,-.003299,
.019,0.0,
.018711,.003299,
.017854,.006498,
.016454,.0095,
.014555,.012213,
.012213,.014555,
.0095,.016454,
.006498,.017854,
.003299,.018711,
0.0,.019,
0.0*
%
%ADD37MACRO37*%
%AMMACRO26*
4,1,16,.04271,.02503,
.046408,.017233,
.048695,.008913,
.049503,.000322,
.048807,-.008279,
.046628,-.016629,
.043032,-.024473,
.04271,-.02503,
.0478,-.03012,
.052304,-.021362,
.055219,-.011955,
.056456,-.002185,
.055978,.007652,
.053799,.017256,
.049985,.026336,
.0478,.03012,
.04271,.02503,
270.*
4,1,16,.02503,-.04271,
.017233,-.046408,
.008913,-.048695,
.000322,-.049503,
-.008279,-.048807,
-.016629,-.046628,
-.024473,-.043032,
-.02503,-.04271,
-.03012,-.0478,
-.021362,-.052304,
-.011955,-.055219,
-.002185,-.056456,
.007652,-.055978,
.017256,-.053799,
.026336,-.049985,
.03012,-.0478,
.02503,-.04271,
270.*
4,1,16,-.04271,-.02503,
-.046408,-.017233,
-.048695,-.008913,
-.049503,-.000322,
-.048807,.008279,
-.046628,.016629,
-.043032,.024473,
-.04271,.02503,
-.0478,.03012,
-.052304,.021362,
-.055219,.011955,
-.056456,.002185,
-.055978,-.007652,
-.053799,-.017256,
-.049985,-.026336,
-.0478,-.03012,
-.04271,-.02503,
270.*
4,1,16,-.02503,.04271,
-.017233,.046408,
-.008913,.048695,
-.000322,.049503,
.008279,.048807,
.016629,.046628,
.024473,.043032,
.02503,.04271,
.03012,.0478,
.021362,.052304,
.011955,.055219,
.002185,.056456,
-.007652,.055978,
-.017256,.053799,
-.026336,.049985,
-.03012,.0478,
-.02503,.04271,
270.*
%
%ADD26MACRO26*%
%AMMACRO44*
4,1,16,.02657,.01597,
.02894,.011114,
.03043,.005919,
.030995,.000545,
.030619,-.004845,
.029313,-.010088,
.027115,-.015025,
.02657,-.01597,
.03164,-.02104,
.034813,-.015226,
.036928,-.00895,
.037921,-.002401,
.037762,.00422,
.036455,.010713,
.034041,.016881,
.03164,.02104,
.02657,.01597,
90.*
4,1,16,.01597,-.02657,
.011114,-.02894,
.005919,-.03043,
.000545,-.030995,
-.004845,-.030619,
-.010088,-.029313,
-.015025,-.027115,
-.01597,-.02657,
-.02104,-.03164,
-.015226,-.034813,
-.00895,-.036928,
-.002401,-.037921,
.00422,-.037762,
.010713,-.036455,
.016881,-.034041,
.02104,-.03164,
.01597,-.02657,
90.*
4,1,16,-.02657,-.01597,
-.02894,-.011114,
-.03043,-.005919,
-.030995,-.000545,
-.030619,.004845,
-.029313,.010088,
-.027115,.015025,
-.02657,.01597,
-.03164,.02104,
-.034813,.015226,
-.036928,.00895,
-.037921,.002401,
-.037762,-.00422,
-.036455,-.010713,
-.034041,-.016881,
-.03164,-.02104,
-.02657,-.01597,
90.*
4,1,16,-.01597,.02657,
-.011114,.02894,
-.005919,.03043,
-.000545,.030995,
.004845,.030619,
.010088,.029313,
.015025,.027115,
.01597,.02657,
.02104,.03164,
.015226,.034813,
.00895,.036928,
.002401,.037921,
-.00422,.037762,
-.010713,.036455,
-.016881,.034041,
-.02104,.03164,
-.01597,.02657,
90.*
%
%ADD44MACRO44*%
%AMMACRO29*
4,1,16,.02511,.01451,
.027248,.009929,
.028558,.005047,
.029001,.000011,
.028562,-.005025,
.027256,-.009909,
.025121,-.014491,
.02511,-.01451,
.0302,-.01959,
.033143,-.014048,
.035079,-.00808,
.035949,-.001865,
.035727,.004405,
.034419,.010542,
.032065,.016359,
.0302,.01959,
.02511,.01451,
0.0*
4,1,16,.01451,-.02511,
.009929,-.027248,
.005047,-.028558,
.000011,-.029001,
-.005025,-.028562,
-.009909,-.027256,
-.014491,-.025121,
-.01451,-.02511,
-.01959,-.0302,
-.014048,-.033143,
-.00808,-.035079,
-.001865,-.035949,
.004405,-.035727,
.010542,-.034419,
.016359,-.032065,
.01959,-.0302,
.01451,-.02511,
0.0*
4,1,16,-.02511,-.01451,
-.027248,-.009929,
-.028558,-.005047,
-.029001,-.000011,
-.028562,.005025,
-.027256,.009909,
-.025121,.014491,
-.02511,.01451,
-.0302,.01959,
-.033143,.014048,
-.035079,.00808,
-.035949,.001865,
-.035727,-.004405,
-.034419,-.010542,
-.032065,-.016359,
-.0302,-.01959,
-.02511,-.01451,
0.0*
4,1,16,-.01451,.02511,
-.009929,.027248,
-.005047,.028558,
-.000011,.029001,
.005025,.028562,
.009909,.027256,
.014491,.025121,
.01451,.02511,
.01959,.0302,
.014048,.033143,
.00808,.035079,
.001865,.035949,
-.004405,.035727,
-.010542,.034419,
-.016359,.032065,
-.01959,.0302,
-.01451,.02511,
0.0*
%
%ADD29MACRO29*%
%AMMACRO46*
4,1,15,.03682,.01914,
.039584,.012455,
.041146,.005393,
.041457,-.001834,
.040509,-.009005,
.03833,-.015903,
.03682,-.01914,
.04197,-.0243,
.045552,-.016643,
.04775,-.00848,
.048497,-.000059,
.047771,.008363,
.045593,.016531,
.042029,.024197,
.04197,.0243,
.03682,.01914,
90.*
4,1,15,.01914,-.03682,
.012455,-.039584,
.005393,-.041146,
-.001834,-.041457,
-.009005,-.040509,
-.015903,-.03833,
-.01914,-.03682,
-.0243,-.04197,
-.016643,-.045552,
-.00848,-.04775,
-.000059,-.048497,
.008363,-.047771,
.016531,-.045593,
.024197,-.042029,
.0243,-.04197,
.01914,-.03682,
90.*
4,1,15,-.03682,-.01914,
-.039584,-.012455,
-.041146,-.005393,
-.041457,.001834,
-.040509,.009005,
-.03833,.015903,
-.03682,.01914,
-.04197,.0243,
-.045552,.016643,
-.04775,.00848,
-.048497,.000059,
-.047771,-.008363,
-.045593,-.016531,
-.042029,-.024197,
-.04197,-.0243,
-.03682,-.01914,
90.*
4,1,15,-.01914,.03682,
-.012455,.039584,
-.005393,.041146,
.001834,.041457,
.009005,.040509,
.015903,.03833,
.01914,.03682,
.0243,.04197,
.016643,.045552,
.00848,.04775,
.000059,.048497,
-.008363,.047771,
-.016531,.045593,
-.024197,.042029,
-.0243,.04197,
-.01914,.03682,
90.*
%
%ADD46MACRO46*%
%AMMACRO45*
4,1,15,-.03682,.01914,
-.039584,.012455,
-.041146,.005393,
-.041457,-.001834,
-.040509,-.009005,
-.03833,-.015903,
-.03682,-.01914,
-.04197,-.0243,
-.045552,-.016643,
-.04775,-.00848,
-.048497,-.000059,
-.047771,.008363,
-.045593,.016531,
-.042029,.024197,
-.04197,.0243,
-.03682,.01914,
90.*
4,1,15,-.01914,-.03682,
-.012455,-.039584,
-.005393,-.041146,
.001834,-.041457,
.009005,-.040509,
.015903,-.03833,
.01914,-.03682,
.0243,-.04197,
.016643,-.045552,
.00848,-.04775,
.000059,-.048497,
-.008363,-.047771,
-.016531,-.045593,
-.024197,-.042029,
-.0243,-.04197,
-.01914,-.03682,
90.*
4,1,15,.03682,-.01914,
.039584,-.012455,
.041146,-.005393,
.041457,.001834,
.040509,.009005,
.03833,.015903,
.03682,.01914,
.04197,.0243,
.045552,.016643,
.04775,.00848,
.048497,.000059,
.047771,-.008363,
.045593,-.016531,
.042029,-.024197,
.04197,-.0243,
.03682,-.01914,
90.*
4,1,15,.01914,.03682,
.012455,.039584,
.005393,.041146,
-.001834,.041457,
-.009005,.040509,
-.015903,.03833,
-.01914,.03682,
-.0243,.04197,
-.016643,.045552,
-.00848,.04775,
-.000059,.048497,
.008363,.047771,
.016531,.045593,
.024197,.042029,
.0243,.04197,
.01914,.03682,
90.*
%
%ADD45MACRO45*%
%ADD36C,.103*%
%AMMACRO13*
4,1,36,0.0,.005,
.000868,.004924,
.00171,.004698,
.0025,.00433,
.003214,.00383,
.00383,.003214,
.00433,.0025,
.004698,.00171,
.004924,.000868,
.005,0.0,
.004924,-.000868,
.004698,-.00171,
.00433,-.0025,
.00383,-.003214,
.003214,-.00383,
.0025,-.00433,
.00171,-.004698,
.000868,-.004924,
0.0,-.005,
-.000868,-.004924,
-.00171,-.004698,
-.0025,-.00433,
-.003214,-.00383,
-.00383,-.003214,
-.00433,-.0025,
-.004698,-.00171,
-.004924,-.000868,
-.005,0.0,
-.004924,.000868,
-.004698,.00171,
-.00433,.0025,
-.00383,.003214,
-.003214,.00383,
-.0025,.00433,
-.00171,.004698,
-.000868,.004924,
0.0,.005,
270.*
%
%ADD13MACRO13*%
%ADD11C,.125*%
%ADD14C,.117*%
%ADD24C,.155*%
%ADD21C,.237*%
%ADD32C,.256*%
%AMMACRO22*
4,1,36,.0025,0.0,
.002462,.000434,
.002349,.000855,
.002165,.00125,
.001915,.001607,
.001607,.001915,
.00125,.002165,
.000855,.002349,
.000434,.002462,
0.0,.0025,
-.000434,.002462,
-.000855,.002349,
-.00125,.002165,
-.001607,.001915,
-.001915,.001607,
-.002165,.00125,
-.002349,.000855,
-.002462,.000434,
-.0025,0.0,
-.002462,-.000434,
-.002349,-.000855,
-.002165,-.00125,
-.001915,-.001607,
-.001607,-.001915,
-.00125,-.002165,
-.000855,-.002349,
-.000434,-.002462,
0.0,-.0025,
.000434,-.002462,
.000855,-.002349,
.00125,-.002165,
.001607,-.001915,
.001915,-.001607,
.002165,-.00125,
.002349,-.000855,
.002462,-.000434,
.0025,0.0,
90.*
%
%ADD22MACRO22*%
%ADD19C,.186*%
%ADD48C,.187*%
%AMMACRO42*
4,1,36,0.0,.019,
-.003299,.018711,
-.006498,.017854,
-.0095,.016454,
-.012213,.014555,
-.014555,.012213,
-.016454,.0095,
-.017854,.006498,
-.018711,.003299,
-.019,0.0,
-.018711,-.003299,
-.017854,-.006498,
-.016454,-.0095,
-.014555,-.012213,
-.012213,-.014555,
-.0095,-.016454,
-.006498,-.017854,
-.003299,-.018711,
0.0,-.019,
.003299,-.018711,
.006498,-.017854,
.0095,-.016454,
.012213,-.014555,
.014555,-.012213,
.016454,-.0095,
.017854,-.006498,
.018711,-.003299,
.019,0.0,
.018711,.003299,
.017854,.006498,
.016454,.0095,
.014555,.012213,
.012213,.014555,
.0095,.016454,
.006498,.017854,
.003299,.018711,
0.0,.019,
270.*
%
%ADD42MACRO42*%
%AMMACRO10*
4,1,36,.0025,0.0,
.002462,.000434,
.002349,.000855,
.002165,.00125,
.001915,.001607,
.001607,.001915,
.00125,.002165,
.000855,.002349,
.000434,.002462,
0.0,.0025,
-.000434,.002462,
-.000855,.002349,
-.00125,.002165,
-.001607,.001915,
-.001915,.001607,
-.002165,.00125,
-.002349,.000855,
-.002462,.000434,
-.0025,0.0,
-.002462,-.000434,
-.002349,-.000855,
-.002165,-.00125,
-.001915,-.001607,
-.001607,-.001915,
-.00125,-.002165,
-.000855,-.002349,
-.000434,-.002462,
0.0,-.0025,
.000434,-.002462,
.000855,-.002349,
.00125,-.002165,
.001607,-.001915,
.001915,-.001607,
.002165,-.00125,
.002349,-.000855,
.002462,-.000434,
.0025,0.0,
0.0*
%
%ADD10MACRO10*%
%AMMACRO18*
4,1,15,.02217,.01156,
.023841,.007535,
.024787,.00328,
.02498,-.001074,
.024414,-.005395,
.023106,-.009553,
.02217,-.01156,
.0273,-.01669,
.029783,-.011696,
.031362,-.006346,
.031987,-.000804,
.031641,.004763,
.030333,.010185,
.028104,.015297,
.0273,.01669,
.02217,.01156,
270.*
4,1,15,.01156,-.02217,
.007535,-.023841,
.00328,-.024787,
-.001074,-.02498,
-.005395,-.024414,
-.009553,-.023106,
-.01156,-.02217,
-.01669,-.0273,
-.011696,-.029783,
-.006346,-.031362,
-.000804,-.031987,
.004763,-.031641,
.010185,-.030333,
.015297,-.028104,
.01669,-.0273,
.01156,-.02217,
270.*
4,1,15,-.02217,-.01156,
-.023841,-.007535,
-.024787,-.00328,
-.02498,.001074,
-.024414,.005395,
-.023106,.009553,
-.02217,.01156,
-.0273,.01669,
-.029783,.011696,
-.031362,.006346,
-.031987,.000804,
-.031641,-.004763,
-.030333,-.010185,
-.028104,-.015297,
-.0273,-.01669,
-.02217,-.01156,
270.*
4,1,15,-.01156,.02217,
-.007535,.023841,
-.00328,.024787,
.001074,.02498,
.005395,.024414,
.009553,.023106,
.01156,.02217,
.01669,.0273,
.011696,.029783,
.006346,.031362,
.000804,.031987,
-.004763,.031641,
-.010185,.030333,
-.015297,.028104,
-.01669,.0273,
-.01156,.02217,
270.*
%
%ADD18MACRO18*%
%AMMACRO34*
4,1,15,.02438,.01377,
.026401,.009327,
.027619,.004601,
.027999,-.000265,
.027527,-.005123,
.02622,-.009825,
.02438,-.01377,
.02948,-.01887,
.032309,-.013464,
.034156,-.007649,
.034965,-.001602,
.034712,.004494,
.033405,.010454,
.031082,.016095,
.02948,.01887,
.02438,.01377,
270.*
4,1,15,.01377,-.02438,
.009327,-.026401,
.004601,-.027619,
-.000265,-.027999,
-.005123,-.027527,
-.009825,-.02622,
-.01377,-.02438,
-.01887,-.02948,
-.013464,-.032309,
-.007649,-.034156,
-.001602,-.034965,
.004494,-.034712,
.010454,-.033405,
.016095,-.031082,
.01887,-.02948,
.01377,-.02438,
270.*
4,1,15,-.02438,-.01377,
-.026401,-.009327,
-.027619,-.004601,
-.027999,.000265,
-.027527,.005123,
-.02622,.009825,
-.02438,.01377,
-.02948,.01887,
-.032309,.013464,
-.034156,.007649,
-.034965,.001602,
-.034712,-.004494,
-.033405,-.010454,
-.031082,-.016095,
-.02948,-.01887,
-.02438,-.01377,
270.*
4,1,15,-.01377,.02438,
-.009327,.026401,
-.004601,.027619,
.000265,.027999,
.005123,.027527,
.009825,.02622,
.01377,.02438,
.01887,.02948,
.013464,.032309,
.007649,.034156,
.001602,.034965,
-.004494,.034712,
-.010454,.033405,
-.016095,.031082,
-.01887,.02948,
-.01377,.02438,
270.*
%
%ADD34MACRO34*%
%AMMACRO15*
4,1,15,.02475,.01414,
.026829,.009627,
.028094,.004822,
.028504,-.000129,
.028049,-.005077,
.026741,-.009871,
.02475,-.01414,
.02984,-.01923,
.032726,-.013756,
.034617,-.007864,
.035457,-.001734,
.03522,.00445,
.033912,.010498,
.031574,.016227,
.02984,.01923,
.02475,.01414,
270.*
4,1,15,.01414,-.02475,
.009627,-.026829,
.004822,-.028094,
-.000129,-.028504,
-.005077,-.028049,
-.009871,-.026741,
-.01414,-.02475,
-.01923,-.02984,
-.013756,-.032726,
-.007864,-.034617,
-.001734,-.035457,
.00445,-.03522,
.010498,-.033912,
.016227,-.031574,
.01923,-.02984,
.01414,-.02475,
270.*
4,1,15,-.02475,-.01414,
-.026829,-.009627,
-.028094,-.004822,
-.028504,.000129,
-.028049,.005077,
-.026741,.009871,
-.02475,.01414,
-.02984,.01923,
-.032726,.013756,
-.034617,.007864,
-.035457,.001734,
-.03522,-.00445,
-.033912,-.010498,
-.031574,-.016227,
-.02984,-.01923,
-.02475,-.01414,
270.*
4,1,15,-.01414,.02475,
-.009627,.026829,
-.004822,.028094,
.000129,.028504,
.005077,.028049,
.009871,.026741,
.01414,.02475,
.01923,.02984,
.013756,.032726,
.007864,.034617,
.001734,.035457,
-.00445,.03522,
-.010498,.033912,
-.016227,.031574,
-.01923,.02984,
-.01414,.02475,
270.*
%
%ADD15MACRO15*%
%AMMACRO47*
4,1,18,.10783,.07955,
.120006,.059617,
.128535,.037873,
.133159,.014977,
.133736,-.008373,
.130251,-.031469,
.122807,-.053609,
.111633,-.074119,
.10783,-.07955,
.11284,-.08455,
.125808,-.063671,
.134953,-.040857,
.139997,-.016802,
.140788,.007763,
.137301,.032093,
.129642,.055447,
.118045,.077117,
.11284,.08455,
.10783,.07955,
270.*
4,1,18,.07955,-.10783,
.059617,-.120006,
.037873,-.128535,
.014977,-.133159,
-.008373,-.133736,
-.031469,-.130251,
-.053609,-.122807,
-.074119,-.111633,
-.07955,-.10783,
-.08455,-.11284,
-.063671,-.125808,
-.040857,-.134953,
-.016802,-.139997,
.007763,-.140788,
.032093,-.137301,
.055447,-.129642,
.077117,-.118045,
.08455,-.11284,
.07955,-.10783,
270.*
4,1,18,-.10783,-.07955,
-.120006,-.059617,
-.128535,-.037873,
-.133159,-.014977,
-.133736,.008373,
-.130251,.031469,
-.122807,.053609,
-.111633,.074119,
-.10783,.07955,
-.11284,.08455,
-.125808,.063671,
-.134953,.040857,
-.139997,.016802,
-.140788,-.007763,
-.137301,-.032093,
-.129642,-.055447,
-.118045,-.077117,
-.11284,-.08455,
-.10783,-.07955,
270.*
4,1,18,-.07955,.10783,
-.059617,.120006,
-.037873,.128535,
-.014977,.133159,
.008373,.133736,
.031469,.130251,
.053609,.122807,
.074119,.111633,
.07955,.10783,
.08455,.11284,
.063671,.125808,
.040857,.134953,
.016802,.139997,
-.007763,.140788,
-.032093,.137301,
-.055447,.129642,
-.077117,.118045,
-.08455,.11284,
-.07955,.10783,
270.*
%
%ADD47MACRO47*%
%AMMACRO39*
4,1,15,.03682,.01914,
.039584,.012455,
.041146,.005393,
.041457,-.001834,
.040509,-.009005,
.03833,-.015903,
.03682,-.01914,
.04197,-.0243,
.045552,-.016643,
.04775,-.00848,
.048497,-.000059,
.047771,.008363,
.045593,.016531,
.042029,.024197,
.04197,.0243,
.03682,.01914,
270.*
4,1,15,.01914,-.03682,
.012455,-.039584,
.005393,-.041146,
-.001834,-.041457,
-.009005,-.040509,
-.015903,-.03833,
-.01914,-.03682,
-.0243,-.04197,
-.016643,-.045552,
-.00848,-.04775,
-.000059,-.048497,
.008363,-.047771,
.016531,-.045593,
.024197,-.042029,
.0243,-.04197,
.01914,-.03682,
270.*
4,1,15,-.03682,-.01914,
-.039584,-.012455,
-.041146,-.005393,
-.041457,.001834,
-.040509,.009005,
-.03833,.015903,
-.03682,.01914,
-.04197,.0243,
-.045552,.016643,
-.04775,.00848,
-.048497,.000059,
-.047771,-.008363,
-.045593,-.016531,
-.042029,-.024197,
-.04197,-.0243,
-.03682,-.01914,
270.*
4,1,15,-.01914,.03682,
-.012455,.039584,
-.005393,.041146,
.001834,.041457,
.009005,.040509,
.015903,.03833,
.01914,.03682,
.0243,.04197,
.016643,.045552,
.00848,.04775,
.000059,.048497,
-.008363,.047771,
-.016531,.045593,
-.024197,.042029,
-.0243,.04197,
-.01914,.03682,
270.*
%
%ADD39MACRO39*%
%AMMACRO31*
4,1,17,.03273,.02212,
.036074,.0161,
.038322,.009592,
.039405,.002791,
.039291,-.004094,
.037983,-.010854,
.035521,-.017285,
.03273,-.02212,
.03775,-.02715,
.041891,-.020182,
.044759,-.012601,
.046267,-.004638,
.04637,.003467,
.045063,.011466,
.042388,.019117,
.038424,.026188,
.03775,.02715,
.03273,.02212,
270.*
4,1,17,.02212,-.03273,
.0161,-.036074,
.009592,-.038322,
.002791,-.039405,
-.004094,-.039291,
-.010854,-.037983,
-.017285,-.035521,
-.02212,-.03273,
-.02715,-.03775,
-.020182,-.041891,
-.012601,-.044759,
-.004638,-.046267,
.003467,-.04637,
.011466,-.045063,
.019117,-.042388,
.026188,-.038424,
.02715,-.03775,
.02212,-.03273,
270.*
4,1,17,-.03273,-.02212,
-.036074,-.0161,
-.038322,-.009592,
-.039405,-.002791,
-.039291,.004094,
-.037983,.010854,
-.035521,.017285,
-.03273,.02212,
-.03775,.02715,
-.041891,.020182,
-.044759,.012601,
-.046267,.004638,
-.04637,-.003467,
-.045063,-.011466,
-.042388,-.019117,
-.038424,-.026188,
-.03775,-.02715,
-.03273,-.02212,
270.*
4,1,17,-.02212,.03273,
-.0161,.036074,
-.009592,.038322,
-.002791,.039405,
.004094,.039291,
.010854,.037983,
.017285,.035521,
.02212,.03273,
.02715,.03775,
.020182,.041891,
.012601,.044759,
.004638,.046267,
-.003467,.04637,
-.011466,.045063,
-.019117,.042388,
-.026188,.038424,
-.02715,.03775,
-.02212,.03273,
270.*
%
%ADD31MACRO31*%
%AMMACRO41*
4,1,15,-.03682,.01914,
-.039584,.012455,
-.041146,.005393,
-.041457,-.001834,
-.040509,-.009005,
-.03833,-.015903,
-.03682,-.01914,
-.04197,-.0243,
-.045552,-.016643,
-.04775,-.00848,
-.048497,-.000059,
-.047771,.008363,
-.045593,.016531,
-.042029,.024197,
-.04197,.0243,
-.03682,.01914,
270.*
4,1,15,-.01914,-.03682,
-.012455,-.039584,
-.005393,-.041146,
.001834,-.041457,
.009005,-.040509,
.015903,-.03833,
.01914,-.03682,
.0243,-.04197,
.016643,-.045552,
.00848,-.04775,
.000059,-.048497,
-.008363,-.047771,
-.016531,-.045593,
-.024197,-.042029,
-.0243,-.04197,
-.01914,-.03682,
270.*
4,1,15,.03682,-.01914,
.039584,-.012455,
.041146,-.005393,
.041457,.001834,
.040509,.009005,
.03833,.015903,
.03682,.01914,
.04197,.0243,
.045552,.016643,
.04775,.00848,
.048497,.000059,
.047771,-.008363,
.045593,-.016531,
.042029,-.024197,
.04197,-.0243,
.03682,-.01914,
270.*
4,1,15,.01914,.03682,
.012455,.039584,
.005393,.041146,
-.001834,.041457,
-.009005,.040509,
-.015903,.03833,
-.01914,.03682,
-.0243,.04197,
-.016643,.045552,
-.00848,.04775,
-.000059,.048497,
.008363,.047771,
.016531,.045593,
.024197,.042029,
.0243,.04197,
.01914,.03682,
270.*
%
%ADD41MACRO41*%
%ADD49C,.02*%
%ADD50C,.006*%
%ADD56C,.07006*%
%ADD59C,.11022*%
%ADD60C,.10006*%
%ADD57C,.11006*%
%ADD55C,.11206*%
%ADD58C,.14306*%
%ADD52C,.12707*%
%ADD53C,.16506*%
%ADD54C,.19606*%
%ADD51C,.28606*%
%ADD61C,.32598*%
G75*
%LPD*%
G75*
G36*
G01X-297025Y-1013390D02*
X3691357D01*
Y1828909D01*
X-297025D01*
Y-1013390D01*
G37*
%LPC*%
G75*
G36*
G01X1048555Y576740D02*
X1049868D01*
Y576736D01*
X1271654D01*
G02X1289335Y559055I0J-17681D01*
G01Y19685D01*
G02X1271654Y2004I-17681J0D01*
G01X19685D01*
G02X2004Y19685I0J17681D01*
G01Y63268D01*
G02X11811Y73075I9807J0D01*
G01X37796D01*
G03X41768Y77047I0J3973D01*
G01Y122323D01*
G03X37796Y126295I-3973J-1D01*
G01X11811D01*
G02X2004Y136102I0J9807D01*
G01Y445787D01*
G02X11811Y455594I9807J0D01*
G01X37795D01*
G03X41768Y459567I0J3973D01*
G01Y504843D01*
G03X37796Y508815I-3973J-1D01*
G01X11811D01*
G02X2004Y518622I0J9807D01*
G01Y559055D01*
G02X19685Y576736I17681J0D01*
G01X1048555D01*
Y576740D01*
G37*
G36*
G01X1283465Y654614D02*
G02X1289339Y648740I0J-5874D01*
G01Y594488D01*
G02X1283465Y588614I-5874J0D01*
G01X607874D01*
G02X602000Y594488I0J5874D01*
G01Y648740D01*
G02X607874Y654614I5874J0D01*
G01X1283465D01*
G37*
%LPD*%
G75*
G36*
G01X1099239Y524880D02*
G02X1100653Y525466I1414J-1413D01*
G01X1175329D01*
G02X1176743Y524880I0J-1999D01*
G01X1181585Y520038D01*
G02X1182171Y518624I-1413J-1414D01*
G01Y497840D01*
G03X1182230Y497698I200J0D01*
G01X1196769Y483159D01*
G03X1196911Y483100I142J141D01*
G01X1258400D01*
G02X1259814Y482514I0J-1999D01*
G01X1264914Y477414D01*
G02X1265500Y476000I-1413J-1414D01*
G01Y302600D01*
G02X1264914Y301186I-1999J0D01*
G01X1260814Y297086D01*
G02X1259400Y296500I-1414J1413D01*
G01X1216111D01*
G03X1215969Y296441I0J-200D01*
G01X1207639Y288111D01*
G02X1206225Y287525I-1414J1413D01*
G01X1183661D01*
G03X1183519Y287466I0J-200D01*
G01X1182230Y286177D01*
G03X1182171Y286035I141J-142D01*
G01Y239982D01*
G02X1181585Y238568I-1999J0D01*
G01X1176710Y233693D01*
G02X1175296Y233107I-1414J1413D01*
G01X1100979D01*
G02X1099565Y233693I0J1999D01*
G01X1093861Y239397D01*
G02X1093275Y240811I1413J1414D01*
G01Y518088D01*
G02X1093861Y519502I1999J0D01*
G01X1099239Y524880D01*
G37*
G36*
G01X637793Y40521D02*
G02X634698Y44000I408J3479D01*
G02X634903Y45182I3502J1D01*
G03Y45318I-188J68D01*
G02X634698Y46500I3297J1181D01*
G02X638058Y50000I3503J0D01*
G03X638215Y50086I-7J200D01*
G02X641100Y51602I2885J-1987D01*
G02X644602Y48100I0J-3502D01*
G02X643351Y45417I-3503J0D01*
G01X643318Y45389D01*
X643281Y45313D01*
X643268Y44930D01*
X643299Y44852D01*
X643330Y44822D01*
G02X644402Y42300I-2431J-2522D01*
G02X640900Y38798I-3502J0D01*
G02X637939Y40429I0J3503D01*
G03X637793Y40521I-169J-107D01*
G37*
G36*
G01X1075308Y93848D02*
G02X1077200Y94402I1890J-2948D01*
G02Y87398I0J-3502D01*
G02X1075308Y87952I-2J3502D01*
G03X1075092I-108J-168D01*
G02X1073200Y87398I-1890J2948D01*
G02Y94402I0J3502D01*
G02X1075092Y93848I2J-3502D01*
G03X1075308I108J168D01*
G37*
G36*
G01X68400Y93092D02*
X67972Y93157D01*
X67879Y93125D01*
X67844Y93087D01*
G02Y106361I-7214J6637D01*
G01X67879Y106323D01*
X67972Y106291D01*
X68400Y106356D01*
X68479Y106415D01*
X68500Y106461D01*
G02X82795Y115526I14295J-6739D01*
G02Y83922I0J-15802D01*
G02X68500Y92987I0J15804D01*
G01X68479Y93033D01*
X68400Y93092D01*
G37*
G36*
G01X1128569Y123243D02*
X1128931D01*
X1129003Y123273D01*
X1129032Y123301D01*
G02X1131500Y124318I2468J-2486D01*
G02X1132919Y124018I1J-3502D01*
G03X1133081I81J183D01*
G02X1134500Y124318I1418J-3202D01*
G02Y117314I0J-3502D01*
G02X1133081Y117614I-1J3502D01*
G03X1132919I-81J-183D01*
G02X1131500Y117314I-1418J3202D01*
G02X1129032Y118331I0J3503D01*
G01X1129003Y118359D01*
X1128931Y118389D01*
X1128569D01*
X1128497Y118359D01*
X1128468Y118331D01*
G02X1126000Y117314I-2468J2486D01*
G02X1124581Y117614I-1J3502D01*
G03X1124419I-81J-183D01*
G02X1123000Y117314I-1418J3202D01*
G02Y124318I0J3502D01*
G02X1124419Y124018I1J-3502D01*
G03X1124581I81J183D01*
G02X1126000Y124318I1418J-3202D01*
G02X1128468Y123301I0J-3503D01*
G01X1128497Y123273D01*
X1128569Y123243D01*
G37*
G36*
G01X1114049Y129633D02*
G02X1115801Y130102I1751J-3033D01*
G02Y123098I0J-3502D01*
G02X1114049Y123567I-1J3502D01*
G02Y129633I1751J3033D01*
G37*
G36*
G01X709714Y144186D02*
Y144630D01*
X709665Y144718D01*
X709621Y144746D01*
G02X707048Y149408I2937J4662D01*
G02X712559Y154918I5511J-1D01*
G02X717221Y152346I0J-5511D01*
G01X717249Y152302D01*
X717337Y152253D01*
X717781D01*
X717869Y152302D01*
X717897Y152346D01*
G02X722559Y154918I4662J-2939D01*
G02X728070Y149408I1J-5510D01*
G02X725497Y144746I-5510J0D01*
G01X725453Y144718D01*
X725404Y144630D01*
Y144186D01*
X725453Y144098D01*
X725497Y144070D01*
G02Y134746I-2937J-4662D01*
G01X725453Y134718D01*
X725404Y134630D01*
Y134186D01*
X725453Y134098D01*
X725497Y134070D01*
G02Y124746I-2937J-4662D01*
G01X725453Y124718D01*
X725404Y124630D01*
Y124186D01*
X725453Y124098D01*
X725497Y124070D01*
G02X728070Y119408I-2937J-4662D01*
G02X722559Y113898I-5511J1D01*
G02X717897Y116470I0J5511D01*
G01X717869Y116514D01*
X717781Y116563D01*
X717337D01*
X717249Y116514D01*
X717221Y116470D01*
G02X712559Y113898I-4662J2939D01*
G02X707048Y119408I-1J5510D01*
G02X709621Y124070I5510J0D01*
G01X709665Y124098D01*
X709714Y124186D01*
Y124630D01*
X709665Y124718D01*
X709621Y124746D01*
G02Y134070I2937J4662D01*
G01X709665Y134098D01*
X709714Y134186D01*
Y134630D01*
X709665Y134718D01*
X709621Y134746D01*
G02Y144070I2937J4662D01*
G01X709665Y144098D01*
X709714Y144186D01*
G37*
G36*
G01X744714D02*
Y144630D01*
X744665Y144718D01*
X744621Y144746D01*
G02X742048Y149408I2937J4662D01*
G02X747559Y154918I5511J-1D01*
G02X752221Y152346I0J-5511D01*
G01X752249Y152302D01*
X752337Y152253D01*
X752781D01*
X752869Y152302D01*
X752897Y152346D01*
G02X757559Y154918I4662J-2939D01*
G02X763070Y149408I1J-5510D01*
G02X760497Y144746I-5510J0D01*
G01X760453Y144718D01*
X760404Y144630D01*
Y144186D01*
X760453Y144098D01*
X760497Y144070D01*
G02Y134746I-2937J-4662D01*
G01X760453Y134718D01*
X760404Y134630D01*
Y134186D01*
X760453Y134098D01*
X760497Y134070D01*
G02Y124746I-2937J-4662D01*
G01X760453Y124718D01*
X760404Y124630D01*
Y124186D01*
X760453Y124098D01*
X760497Y124070D01*
G02X763070Y119408I-2937J-4662D01*
G02X757559Y113898I-5511J1D01*
G02X752897Y116470I0J5511D01*
G01X752869Y116514D01*
X752781Y116563D01*
X752337D01*
X752249Y116514D01*
X752221Y116470D01*
G02X747559Y113898I-4662J2939D01*
G02X742048Y119408I-1J5510D01*
G02X744621Y124070I5510J0D01*
G01X744665Y124098D01*
X744714Y124186D01*
Y124630D01*
X744665Y124718D01*
X744621Y124746D01*
G02Y134070I2937J4662D01*
G01X744665Y134098D01*
X744714Y134186D01*
Y134630D01*
X744665Y134718D01*
X744621Y134746D01*
G02Y144070I2937J4662D01*
G01X744665Y144098D01*
X744714Y144186D01*
G37*
G36*
G01X779714D02*
Y144630D01*
X779665Y144718D01*
X779621Y144746D01*
G02X777048Y149408I2937J4662D01*
G02X782559Y154918I5511J-1D01*
G02X787221Y152346I0J-5511D01*
G01X787249Y152302D01*
X787337Y152253D01*
X787781D01*
X787869Y152302D01*
X787897Y152346D01*
G02X792559Y154918I4662J-2939D01*
G02X798070Y149408I1J-5510D01*
G02X795497Y144746I-5510J0D01*
G01X795453Y144718D01*
X795404Y144630D01*
Y144186D01*
X795453Y144098D01*
X795497Y144070D01*
G02Y134746I-2937J-4662D01*
G01X795453Y134718D01*
X795404Y134630D01*
Y134186D01*
X795453Y134098D01*
X795497Y134070D01*
G02Y124746I-2937J-4662D01*
G01X795453Y124718D01*
X795404Y124630D01*
Y124186D01*
X795453Y124098D01*
X795497Y124070D01*
G02X798070Y119408I-2937J-4662D01*
G02X792559Y113898I-5511J1D01*
G02X787897Y116470I0J5511D01*
G01X787869Y116514D01*
X787781Y116563D01*
X787337D01*
X787249Y116514D01*
X787221Y116470D01*
G02X782559Y113898I-4662J2939D01*
G02X777048Y119408I-1J5510D01*
G02X779621Y124070I5510J0D01*
G01X779665Y124098D01*
X779714Y124186D01*
Y124630D01*
X779665Y124718D01*
X779621Y124746D01*
G02Y134070I2937J4662D01*
G01X779665Y134098D01*
X779714Y134186D01*
Y134630D01*
X779665Y134718D01*
X779621Y134746D01*
G02Y144070I2937J4662D01*
G01X779665Y144098D01*
X779714Y144186D01*
G37*
G36*
G01X1138250Y164134D02*
G02X1140000Y164602I1749J-3034D01*
G02Y157598I0J-3502D01*
G02X1138250Y158066I-1J3502D01*
G03X1138050I-100J-173D01*
G02X1136300Y157598I-1749J3034D01*
G02Y164602I0J3502D01*
G02X1138050Y164134I1J-3502D01*
G03X1138250I100J173D01*
G37*
G36*
G01X398907Y154463D02*
Y154907D01*
X398858Y154995D01*
X398814Y155023D01*
G02X396242Y159685I2939J4662D01*
G02X401752Y165196I5510J1D01*
G02X406414Y162623I0J-5510D01*
G01X406442Y162579D01*
X406530Y162530D01*
X406974D01*
X407062Y162579D01*
X407090Y162623D01*
G02X411752Y165196I4662J-2937D01*
G02X417262Y159685I-1J-5511D01*
G02X414690Y155023I-5511J0D01*
G01X414646Y154995D01*
X414597Y154907D01*
Y154463D01*
X414646Y154375D01*
X414690Y154347D01*
G02Y145023I-2939J-4662D01*
G01X414646Y144995D01*
X414597Y144907D01*
Y144463D01*
X414646Y144375D01*
X414690Y144347D01*
G02Y135023I-2939J-4662D01*
G01X414646Y134995D01*
X414597Y134907D01*
Y134463D01*
X414646Y134375D01*
X414690Y134347D01*
G02X417262Y129685I-2939J-4662D01*
G02X411752Y124174I-5510J-1D01*
G02X407090Y126747I0J5510D01*
G01X407062Y126791D01*
X406974Y126840D01*
X406530D01*
X406442Y126791D01*
X406414Y126747D01*
G02X401752Y124174I-4662J2937D01*
G02X396242Y129685I1J5511D01*
G02X398814Y134347I5511J0D01*
G01X398858Y134375D01*
X398907Y134463D01*
Y134907D01*
X398858Y134995D01*
X398814Y135023D01*
G02Y144347I2939J4662D01*
G01X398858Y144375D01*
X398907Y144463D01*
Y144907D01*
X398858Y144995D01*
X398814Y145023D01*
G02Y154347I2939J4662D01*
G01X398858Y154375D01*
X398907Y154463D01*
G37*
G36*
G01X433907D02*
Y154907D01*
X433858Y154995D01*
X433814Y155023D01*
G02X431242Y159685I2939J4662D01*
G02X436752Y165196I5510J1D01*
G02X441414Y162623I0J-5510D01*
G01X441442Y162579D01*
X441530Y162530D01*
X441974D01*
X442062Y162579D01*
X442090Y162623D01*
G02X446752Y165196I4662J-2937D01*
G02X452262Y159685I-1J-5511D01*
G02X449690Y155023I-5511J0D01*
G01X449646Y154995D01*
X449597Y154907D01*
Y154463D01*
X449646Y154375D01*
X449690Y154347D01*
G02Y145023I-2939J-4662D01*
G01X449646Y144995D01*
X449597Y144907D01*
Y144463D01*
X449646Y144375D01*
X449690Y144347D01*
G02Y135023I-2939J-4662D01*
G01X449646Y134995D01*
X449597Y134907D01*
Y134463D01*
X449646Y134375D01*
X449690Y134347D01*
G02X452262Y129685I-2939J-4662D01*
G02X446752Y124174I-5510J-1D01*
G02X442090Y126747I0J5510D01*
G01X442062Y126791D01*
X441974Y126840D01*
X441530D01*
X441442Y126791D01*
X441414Y126747D01*
G02X436752Y124174I-4662J2937D01*
G02X431242Y129685I1J5511D01*
G02X433814Y134347I5511J0D01*
G01X433858Y134375D01*
X433907Y134463D01*
Y134907D01*
X433858Y134995D01*
X433814Y135023D01*
G02Y144347I2939J4662D01*
G01X433858Y144375D01*
X433907Y144463D01*
Y144907D01*
X433858Y144995D01*
X433814Y145023D01*
G02Y154347I2939J4662D01*
G01X433858Y154375D01*
X433907Y154463D01*
G37*
G36*
G01X468907D02*
Y154907D01*
X468858Y154995D01*
X468814Y155023D01*
G02X466242Y159685I2939J4662D01*
G02X471752Y165196I5510J1D01*
G02X476414Y162623I0J-5510D01*
G01X476442Y162579D01*
X476530Y162530D01*
X476974D01*
X477062Y162579D01*
X477090Y162623D01*
G02X481752Y165196I4662J-2937D01*
G02X487262Y159685I-1J-5511D01*
G02X484690Y155023I-5511J0D01*
G01X484646Y154995D01*
X484597Y154907D01*
Y154463D01*
X484646Y154375D01*
X484690Y154347D01*
G02Y145023I-2939J-4662D01*
G01X484646Y144995D01*
X484597Y144907D01*
Y144463D01*
X484646Y144375D01*
X484690Y144347D01*
G02Y135023I-2939J-4662D01*
G01X484646Y134995D01*
X484597Y134907D01*
Y134463D01*
X484646Y134375D01*
X484690Y134347D01*
G02X487262Y129685I-2939J-4662D01*
G02X481752Y124174I-5510J-1D01*
G02X477090Y126747I0J5510D01*
G01X477062Y126791D01*
X476974Y126840D01*
X476530D01*
X476442Y126791D01*
X476414Y126747D01*
G02X471752Y124174I-4662J2937D01*
G02X466242Y129685I1J5511D01*
G02X468814Y134347I5511J0D01*
G01X468858Y134375D01*
X468907Y134463D01*
Y134907D01*
X468858Y134995D01*
X468814Y135023D01*
G02Y144347I2939J4662D01*
G01X468858Y144375D01*
X468907Y144463D01*
Y144907D01*
X468858Y144995D01*
X468814Y145023D01*
G02Y154347I2939J4662D01*
G01X468858Y154375D01*
X468907Y154463D01*
G37*
G36*
G01X1181839Y169249D02*
G02X1183021Y169454I1181J-3297D01*
G02X1184203Y169249I1J-3502D01*
G03X1184339I68J188D01*
G02X1185521Y169454I1181J-3297D01*
G02X1186928Y169160I2J-3502D01*
G03X1187094Y169162I81J183D01*
G02X1188600Y169502I1505J-3162D01*
G02X1192102Y166000I0J-3502D01*
G02X1191763Y164496I-3502J-1D01*
G03X1191764Y164322I181J-86D01*
G02X1192120Y162782I-3146J-1538D01*
G02X1188618Y159280I-3502J0D01*
G02X1186979Y159687I0J3502D01*
G03X1186812Y159696I-93J-177D01*
G02X1185521Y159450I-1289J3256D01*
G02X1184339Y159655I-1J3502D01*
G03X1184203I-68J-188D01*
G02X1183021Y159450I-1181J3297D01*
G02X1181839Y159655I-1J3502D01*
G03X1181703I-68J-188D01*
G02X1180521Y159450I-1181J3297D01*
G02X1179102Y159750I-1J3502D01*
G03X1178940I-81J-183D01*
G02X1177521Y159450I-1418J3202D01*
G02X1174018Y162952I-1J3502D01*
G02X1174319Y164371I3503J-2D01*
G03Y164533I-183J81D01*
G02X1174018Y165952I3202J1421D01*
G02X1177521Y169454I3503J-1D01*
G02X1178940Y169154I1J-3502D01*
G03X1179102I81J183D01*
G02X1180521Y169454I1418J-3202D01*
G02X1181703Y169249I1J-3502D01*
G03X1181839I68J188D01*
G37*
G36*
G01X1018570Y169974D02*
X1018623Y170080D01*
G03X1018636Y170225I-179J89D01*
G02X1018498Y171200I3364J973D01*
G02X1025502I3502J0D01*
G02X1023239Y167924I-3503J0D01*
G03X1023130Y167826I70J-187D01*
G01X1023077Y167720D01*
G03X1023064Y167575I179J-89D01*
G02X1023202Y166600I-3364J-973D01*
G02X1023053Y165589I-3502J0D01*
G01X1023042Y165551D01*
X1023049Y165475D01*
X1023211Y165158D01*
X1023269Y165108D01*
X1023306Y165095D01*
G02X1025670Y161783I-1138J-3312D01*
G02X1024458Y159133I-3503J0D01*
G01X1024424Y159104D01*
X1024389Y159026D01*
Y158634D01*
X1024424Y158556D01*
X1024458Y158527D01*
G02X1025670Y155877I-2291J-2650D01*
G02X1022168Y152374I-3502J-1D01*
G02X1021810Y152393I6J3503D01*
G01X1021764Y152398D01*
X1021678Y152366D01*
X1021395Y152070D01*
X1021367Y151983D01*
X1021374Y151936D01*
G02X1021412Y151424I-3465J-515D01*
G02X1014406I-3503J0D01*
G02X1014645Y152693I3503J-3D01*
G03X1014641Y152848I-187J73D01*
G02X1014334Y154280I3196J1434D01*
G02X1015483Y156874I3503J0D01*
G03X1015548Y157037I-134J148D01*
G02X1015538Y157310I3492J265D01*
G02X1015837Y158728I3502J2D01*
G03Y158891I-183J82D01*
G02X1015528Y160330I3193J1438D01*
G02X1017278Y163363I3503J0D01*
G01X1017320Y163387D01*
X1017372Y163467D01*
X1017417Y163885D01*
X1017383Y163973D01*
X1017347Y164006D01*
G02X1016198Y166600I2354J2594D01*
G02X1018461Y169876I3503J0D01*
G03X1018570Y169974I-70J187D01*
G37*
G36*
G01X1138250Y175334D02*
G02X1140000Y175802I1749J-3034D01*
G02Y168798I0J-3502D01*
G02X1138250Y169266I-1J3502D01*
G03X1138050I-100J-173D01*
G02X1136300Y168798I-1749J3034D01*
G02Y175802I0J3502D01*
G02X1138050Y175334I1J-3502D01*
G03X1138250I100J173D01*
G37*
G36*
G01X1141998Y186729D02*
G02X1143490Y187062I1491J-3169D01*
G02Y180058I0J-3502D01*
G02X1141998Y180391I-1J3502D01*
G03X1141828I-85J-181D01*
G02X1140336Y180058I-1491J3169D01*
G02Y187062I0J3502D01*
G02X1141828Y186729I1J-3502D01*
G03X1141998I85J181D01*
G37*
G36*
G01X1019816Y188686D02*
G02X1020116Y187267I-3202J-1418D01*
G02X1013112I-3502J0D01*
G02X1013412Y188686I3502J1D01*
G03Y188848I-183J81D01*
G02X1013112Y190267I3202J1418D01*
G02X1020116I3502J0D01*
G02X1019816Y188848I-3502J-1D01*
G03Y188686I183J-81D01*
G37*
G36*
G01X1164671Y187837D02*
Y198772D01*
G02X1165171Y199272I500J0D01*
G01X1169952D01*
G02X1170452Y198772I0J-500D01*
G01Y187837D01*
G02X1170253Y187438I-500J0D01*
G01X1170219Y187412D01*
X1170178Y187339D01*
X1170142Y186961D01*
X1170169Y186881D01*
X1170197Y186850D01*
G02X1171102Y184500I-2597J-2349D01*
G02X1170548Y182608I-3502J-2D01*
G03Y182392I168J-108D01*
G02X1171102Y180500I-2948J-1890D01*
G02X1167600Y176998I-3502J0D01*
G02X1166632Y177134I-2J3502D01*
G01X1166581Y177148D01*
X1166480Y177124D01*
X1166151Y176820D01*
X1166119Y176720D01*
X1166130Y176668D01*
G02X1166202Y175959I-3430J-707D01*
G02X1162700Y172456I-3502J-1D01*
G02X1161487Y172673I1J3503D01*
G03X1161352Y172674I-69J-188D01*
G02X1160200Y172480I-1149J3308D01*
G02X1156715Y175628I0J3503D01*
G03X1156597Y175791I-199J-20D01*
G02X1154498Y179000I1403J3209D01*
G02X1158000Y182502I3502J0D01*
G02X1161435Y179684I0J-3503D01*
G01X1161443Y179645D01*
X1161488Y179578D01*
X1161797Y179378D01*
X1161877Y179364D01*
X1161917Y179373D01*
G02X1162700Y179462I785J-3414D01*
G02X1163668Y179325I-2J-3503D01*
G01X1163719Y179311D01*
X1163820Y179335D01*
X1164149Y179639D01*
X1164181Y179739D01*
X1164170Y179791D01*
G02X1164098Y180500I3430J707D01*
G02X1164652Y182392I3502J2D01*
G03Y182608I-168J108D01*
G02X1164098Y184500I2948J1890D01*
G02X1164976Y186820I3502J1D01*
G01X1165005Y186853D01*
X1165030Y186935D01*
X1164979Y187322D01*
X1164933Y187395D01*
X1164896Y187419D01*
G02X1164671Y187837I276J418D01*
G37*
G36*
G01X1090702Y199419D02*
G02X1091002Y198000I-3202J-1418D01*
G02X1083998I-3502J0D01*
G02X1084298Y199419I3502J1D01*
G03Y199581I-183J81D01*
G02X1083998Y201000I3202J1418D01*
G02X1091002I3502J0D01*
G02X1090702Y199581I-3502J-1D01*
G03Y199419I183J-81D01*
G37*
G36*
G01X587867Y200690D02*
G02X586998Y203000I2633J2309D01*
G02X587203Y204182I3502J1D01*
G03Y204318I-188J68D01*
G02X586998Y205500I3297J1181D01*
G02X594002I3502J0D01*
G02X593797Y204318I-3502J-1D01*
G03Y204182I188J-68D01*
G02X594002Y203000I-3297J-1181D01*
G02X593133Y200690I-3502J-1D01*
G03X593083Y200559I150J-132D01*
G01Y200441D01*
G03X593133Y200310I200J1D01*
G02X594002Y198000I-2633J-2309D01*
G02X593797Y196818I-3502J-1D01*
G03Y196682I188J-68D01*
G02X594002Y195500I-3297J-1181D01*
G02X586998I-3502J0D01*
G02X587203Y196682I3502J1D01*
G03Y196818I-188J68D01*
G02X586998Y198000I3297J1181D01*
G02X587867Y200310I3502J1D01*
G03X587917Y200441I-150J132D01*
G01Y200559D01*
G03X587867Y200690I-200J-1D01*
G37*
G36*
G01X609367D02*
G02X608498Y203000I2633J2309D01*
G02X608703Y204182I3502J1D01*
G03Y204318I-188J68D01*
G02X608498Y205500I3297J1181D01*
G02X615502I3502J0D01*
G02X615297Y204318I-3502J-1D01*
G03Y204182I188J-68D01*
G02X615502Y203000I-3297J-1181D01*
G02X614633Y200690I-3502J-1D01*
G03X614583Y200559I150J-132D01*
G01Y200441D01*
G03X614633Y200310I200J1D01*
G02X615502Y198000I-2633J-2309D01*
G02X615297Y196818I-3502J-1D01*
G03Y196682I188J-68D01*
G02X615502Y195500I-3297J-1181D01*
G02X608498I-3502J0D01*
G02X608703Y196682I3502J1D01*
G03Y196818I-188J68D01*
G02X608498Y198000I3297J1181D01*
G02X609367Y200310I3502J1D01*
G03X609417Y200441I-150J132D01*
G01Y200559D01*
G03X609367Y200690I-200J-1D01*
G37*
G36*
G01X630867D02*
G02X629998Y203000I2633J2309D01*
G02X630203Y204182I3502J1D01*
G03Y204318I-188J68D01*
G02X629998Y205500I3297J1181D01*
G02X637002I3502J0D01*
G02X636797Y204318I-3502J-1D01*
G03Y204182I188J-68D01*
G02X637002Y203000I-3297J-1181D01*
G02X636133Y200690I-3502J-1D01*
G03X636083Y200559I150J-132D01*
G01Y200441D01*
G03X636133Y200310I200J1D01*
G02X637002Y198000I-2633J-2309D01*
G02X636797Y196818I-3502J-1D01*
G03Y196682I188J-68D01*
G02X637002Y195500I-3297J-1181D01*
G02X629998I-3502J0D01*
G02X630203Y196682I3502J1D01*
G03Y196818I-188J68D01*
G02X629998Y198000I3297J1181D01*
G02X630867Y200310I3502J1D01*
G03X630917Y200441I-150J132D01*
G01Y200559D01*
G03X630867Y200690I-200J-1D01*
G37*
G36*
G01X652367D02*
G02X651498Y203000I2633J2309D01*
G02X651703Y204182I3502J1D01*
G03Y204318I-188J68D01*
G02X651498Y205500I3297J1181D01*
G02X658502I3502J0D01*
G02X658297Y204318I-3502J-1D01*
G03Y204182I188J-68D01*
G02X658502Y203000I-3297J-1181D01*
G02X657633Y200690I-3502J-1D01*
G03X657583Y200559I150J-132D01*
G01Y200441D01*
G03X657633Y200310I200J1D01*
G02X658502Y198000I-2633J-2309D01*
G02X658297Y196818I-3502J-1D01*
G03Y196682I188J-68D01*
G02X658502Y195500I-3297J-1181D01*
G02X651498I-3502J0D01*
G02X651703Y196682I3502J1D01*
G03Y196818I-188J68D01*
G02X651498Y198000I3297J1181D01*
G02X652367Y200310I3502J1D01*
G03X652417Y200441I-150J132D01*
G01Y200559D01*
G03X652367Y200690I-200J-1D01*
G37*
G36*
G01X673867D02*
G02X672998Y203000I2633J2309D01*
G02X673203Y204182I3502J1D01*
G03Y204318I-188J68D01*
G02X672998Y205500I3297J1181D01*
G02X680002I3502J0D01*
G02X679797Y204318I-3502J-1D01*
G03Y204182I188J-68D01*
G02X680002Y203000I-3297J-1181D01*
G02X679133Y200690I-3502J-1D01*
G03X679083Y200559I150J-132D01*
G01Y200441D01*
G03X679133Y200310I200J1D01*
G02X680002Y198000I-2633J-2309D01*
G02X679797Y196818I-3502J-1D01*
G03Y196682I188J-68D01*
G02X680002Y195500I-3297J-1181D01*
G02X672998I-3502J0D01*
G02X673203Y196682I3502J1D01*
G03Y196818I-188J68D01*
G02X672998Y198000I3297J1181D01*
G02X673867Y200310I3502J1D01*
G03X673917Y200441I-150J132D01*
G01Y200559D01*
G03X673867Y200690I-200J-1D01*
G37*
G36*
G01X695357D02*
G02X694488Y203000I2633J2309D01*
G02X694693Y204182I3502J1D01*
G03Y204318I-188J68D01*
G02X694488Y205500I3297J1181D01*
G02X701492I3502J0D01*
G02X701287Y204318I-3502J-1D01*
G03Y204182I188J-68D01*
G02X701492Y203000I-3297J-1181D01*
G02X700623Y200690I-3502J-1D01*
G03X700573Y200559I150J-132D01*
G01Y200441D01*
G03X700623Y200310I200J1D01*
G02X701492Y198000I-2633J-2309D01*
G02X701287Y196818I-3502J-1D01*
G03Y196682I188J-68D01*
G02X701492Y195500I-3297J-1181D01*
G02X694488I-3502J0D01*
G02X694693Y196682I3502J1D01*
G03Y196818I-188J68D01*
G02X694488Y198000I3297J1181D01*
G02X695357Y200310I3502J1D01*
G03X695407Y200441I-150J132D01*
G01Y200559D01*
G03X695357Y200690I-200J-1D01*
G37*
G36*
G01X716857D02*
G02X715988Y203000I2633J2309D01*
G02X716193Y204182I3502J1D01*
G03Y204318I-188J68D01*
G02X715988Y205500I3297J1181D01*
G02X722992I3502J0D01*
G02X722787Y204318I-3502J-1D01*
G03Y204182I188J-68D01*
G02X722992Y203000I-3297J-1181D01*
G02X722123Y200690I-3502J-1D01*
G03X722073Y200559I150J-132D01*
G01Y200441D01*
G03X722123Y200310I200J1D01*
G02X722992Y198000I-2633J-2309D01*
G02X722787Y196818I-3502J-1D01*
G03Y196682I188J-68D01*
G02X722992Y195500I-3297J-1181D01*
G02X715988I-3502J0D01*
G02X716193Y196682I3502J1D01*
G03Y196818I-188J68D01*
G02X715988Y198000I3297J1181D01*
G02X716857Y200310I3502J1D01*
G03X716907Y200441I-150J132D01*
G01Y200559D01*
G03X716857Y200690I-200J-1D01*
G37*
G36*
G01X173348Y199403D02*
G02X171158Y202650I1312J3247D01*
G02X171501Y204164I3503J2D01*
G03Y204336I-180J86D01*
G02X171158Y205850I3160J1512D01*
G02X178162I3502J0D01*
G02X177819Y204336I-3503J-2D01*
G03Y204164I180J-86D01*
G02X178162Y202650I-3160J-1512D01*
G02X177677Y200871I-3502J-1D01*
G01X177655Y200834D01*
X177646Y200747D01*
X177772Y200377D01*
X177832Y200314D01*
X177872Y200297D01*
G02X177932Y200273I-1271J-3264D01*
G03X178088I78J184D01*
G02X179460Y200552I1370J-3223D01*
G02X180784Y200292I0J-3501D01*
G03X180936I76J186D01*
G02X182260Y200552I1324J-3241D01*
G02Y193548I0J-3502D01*
G02X180936Y193808I0J3501D01*
G03X180784I-76J-186D01*
G02X179460Y193548I-1324J3241D01*
G02X178088Y193827I-2J3502D01*
G03X177932I-78J-184D01*
G02X176560Y193548I-1370J3223D01*
G02X173058Y197050I0J3502D01*
G02X173543Y198829I3502J1D01*
G01X173565Y198866D01*
X173574Y198953D01*
X173448Y199323D01*
X173388Y199386D01*
X173348Y199403D01*
G37*
G36*
G01X280367Y201190D02*
G02X279498Y203500I2633J2309D01*
G02X279703Y204682I3502J1D01*
G03Y204818I-188J68D01*
G02X279498Y206000I3297J1181D01*
G02X286502I3502J0D01*
G02X286297Y204818I-3502J-1D01*
G03Y204682I188J-68D01*
G02X286502Y203500I-3297J-1181D01*
G02X285633Y201190I-3502J-1D01*
G03X285583Y201059I150J-132D01*
G01Y200941D01*
G03X285633Y200810I200J1D01*
G02X286502Y198500I-2633J-2309D01*
G02X286297Y197318I-3502J-1D01*
G03Y197182I188J-68D01*
G02X286502Y196000I-3297J-1181D01*
G02X279498I-3502J0D01*
G02X279703Y197182I3502J1D01*
G03Y197318I-188J68D01*
G02X279498Y198500I3297J1181D01*
G02X280367Y200810I3502J1D01*
G03X280417Y200941I-150J132D01*
G01Y201059D01*
G03X280367Y201190I-200J-1D01*
G37*
G36*
G01X301867D02*
G02X300998Y203500I2633J2309D01*
G02X301203Y204682I3502J1D01*
G03Y204818I-188J68D01*
G02X300998Y206000I3297J1181D01*
G02X308002I3502J0D01*
G02X307797Y204818I-3502J-1D01*
G03Y204682I188J-68D01*
G02X308002Y203500I-3297J-1181D01*
G02X307133Y201190I-3502J-1D01*
G03X307083Y201059I150J-132D01*
G01Y200941D01*
G03X307133Y200810I200J1D01*
G02X308002Y198500I-2633J-2309D01*
G02X307797Y197318I-3502J-1D01*
G03Y197182I188J-68D01*
G02X308002Y196000I-3297J-1181D01*
G02X300998I-3502J0D01*
G02X301203Y197182I3502J1D01*
G03Y197318I-188J68D01*
G02X300998Y198500I3297J1181D01*
G02X301867Y200810I3502J1D01*
G03X301917Y200941I-150J132D01*
G01Y201059D01*
G03X301867Y201190I-200J-1D01*
G37*
G36*
G01X323367D02*
G02X322498Y203500I2633J2309D01*
G02X322703Y204682I3502J1D01*
G03Y204818I-188J68D01*
G02X322498Y206000I3297J1181D01*
G02X329502I3502J0D01*
G02X329297Y204818I-3502J-1D01*
G03Y204682I188J-68D01*
G02X329502Y203500I-3297J-1181D01*
G02X328633Y201190I-3502J-1D01*
G03X328583Y201059I150J-132D01*
G01Y200941D01*
G03X328633Y200810I200J1D01*
G02X329502Y198500I-2633J-2309D01*
G02X329297Y197318I-3502J-1D01*
G03Y197182I188J-68D01*
G02X329502Y196000I-3297J-1181D01*
G02X322498I-3502J0D01*
G02X322703Y197182I3502J1D01*
G03Y197318I-188J68D01*
G02X322498Y198500I3297J1181D01*
G02X323367Y200810I3502J1D01*
G03X323417Y200941I-150J132D01*
G01Y201059D01*
G03X323367Y201190I-200J-1D01*
G37*
G36*
G01X344867D02*
G02X343998Y203500I2633J2309D01*
G02X344203Y204682I3502J1D01*
G03Y204818I-188J68D01*
G02X343998Y206000I3297J1181D01*
G02X351002I3502J0D01*
G02X350797Y204818I-3502J-1D01*
G03Y204682I188J-68D01*
G02X351002Y203500I-3297J-1181D01*
G02X350133Y201190I-3502J-1D01*
G03X350083Y201059I150J-132D01*
G01Y200941D01*
G03X350133Y200810I200J1D01*
G02X351002Y198500I-2633J-2309D01*
G02X350797Y197318I-3502J-1D01*
G03Y197182I188J-68D01*
G02X351002Y196000I-3297J-1181D01*
G02X343998I-3502J0D01*
G02X344203Y197182I3502J1D01*
G03Y197318I-188J68D01*
G02X343998Y198500I3297J1181D01*
G02X344867Y200810I3502J1D01*
G03X344917Y200941I-150J132D01*
G01Y201059D01*
G03X344867Y201190I-200J-1D01*
G37*
G36*
G01X366367D02*
G02X365498Y203500I2633J2309D01*
G02X365703Y204682I3502J1D01*
G03Y204818I-188J68D01*
G02X365498Y206000I3297J1181D01*
G02X372502I3502J0D01*
G02X372297Y204818I-3502J-1D01*
G03Y204682I188J-68D01*
G02X372502Y203500I-3297J-1181D01*
G02X371633Y201190I-3502J-1D01*
G03X371583Y201059I150J-132D01*
G01Y200941D01*
G03X371633Y200810I200J1D01*
G02X372502Y198500I-2633J-2309D01*
G02X372297Y197318I-3502J-1D01*
G03Y197182I188J-68D01*
G02X372502Y196000I-3297J-1181D01*
G02X365498I-3502J0D01*
G02X365703Y197182I3502J1D01*
G03Y197318I-188J68D01*
G02X365498Y198500I3297J1181D01*
G02X366367Y200810I3502J1D01*
G03X366417Y200941I-150J132D01*
G01Y201059D01*
G03X366367Y201190I-200J-1D01*
G37*
G36*
G01X387867D02*
G02X386998Y203500I2633J2309D01*
G02X387203Y204682I3502J1D01*
G03Y204818I-188J68D01*
G02X386998Y206000I3297J1181D01*
G02X394002I3502J0D01*
G02X393797Y204818I-3502J-1D01*
G03Y204682I188J-68D01*
G02X394002Y203500I-3297J-1181D01*
G02X393133Y201190I-3502J-1D01*
G03X393083Y201059I150J-132D01*
G01Y200941D01*
G03X393133Y200810I200J1D01*
G02X394002Y198500I-2633J-2309D01*
G02X393797Y197318I-3502J-1D01*
G03Y197182I188J-68D01*
G02X394002Y196000I-3297J-1181D01*
G02X386998I-3502J0D01*
G02X387203Y197182I3502J1D01*
G03Y197318I-188J68D01*
G02X386998Y198500I3297J1181D01*
G02X387867Y200810I3502J1D01*
G03X387917Y200941I-150J132D01*
G01Y201059D01*
G03X387867Y201190I-200J-1D01*
G37*
G36*
G01X409367D02*
G02X408498Y203500I2633J2309D01*
G02X408703Y204682I3502J1D01*
G03Y204818I-188J68D01*
G02X408498Y206000I3297J1181D01*
G02X415502I3502J0D01*
G02X415297Y204818I-3502J-1D01*
G03Y204682I188J-68D01*
G02X415502Y203500I-3297J-1181D01*
G02X414633Y201190I-3502J-1D01*
G03X414583Y201059I150J-132D01*
G01Y200941D01*
G03X414633Y200810I200J1D01*
G02X415502Y198500I-2633J-2309D01*
G02X415297Y197318I-3502J-1D01*
G03Y197182I188J-68D01*
G02X415502Y196000I-3297J-1181D01*
G02X408498I-3502J0D01*
G02X408703Y197182I3502J1D01*
G03Y197318I-188J68D01*
G02X408498Y198500I3297J1181D01*
G02X409367Y200810I3502J1D01*
G03X409417Y200941I-150J132D01*
G01Y201059D01*
G03X409367Y201190I-200J-1D01*
G37*
G36*
G01X190958Y206781D02*
G02X190658Y208200I3202J1418D01*
G02X194160Y211702I3502J0D01*
G02X195579Y211402I1J-3502D01*
G03X195741I81J183D01*
G02X197160Y211702I1418J-3202D01*
G02X198579Y211402I1J-3502D01*
G03X198741I81J183D01*
G02X200160Y211702I1418J-3202D01*
G02X203662Y208200I0J-3502D01*
G02X203362Y206781I-3502J-1D01*
G03Y206619I183J-81D01*
G02X203662Y205200I-3202J-1418D01*
G02X200160Y201698I-3502J0D01*
G02X198741Y201998I-1J3502D01*
G03X198579I-81J-183D01*
G02X197160Y201698I-1418J3202D01*
G02X195741Y201998I-1J3502D01*
G03X195579I-81J-183D01*
G02X194160Y201698I-1418J3202D01*
G02X190658Y205200I0J3502D01*
G02X190958Y206619I3502J1D01*
G03Y206781I-183J81D01*
G37*
G36*
G01X188462Y206769D02*
G02X188762Y205350I-3202J-1418D01*
G02X181758I-3502J0D01*
G02X182058Y206769I3502J1D01*
G03Y206931I-183J81D01*
G02X181758Y208350I3202J1418D01*
G02X188762I3502J0D01*
G02X188462Y206931I-3502J-1D01*
G03Y206769I183J-81D01*
G37*
G36*
G01X1168298Y209581D02*
G02X1167998Y211000I3202J1418D01*
G02X1168298Y212419I3502J1D01*
G03Y212581I-183J81D01*
G02X1167998Y214000I3202J1418D01*
G02X1171500Y217502I3502J0D01*
G02X1172919Y217202I1J-3502D01*
G03X1173081I81J183D01*
G02X1174500Y217502I1418J-3202D01*
G02X1178002Y214000I0J-3502D01*
G02X1177702Y212581I-3502J-1D01*
G03Y212419I183J-81D01*
G02X1178002Y211000I-3202J-1418D01*
G02X1177702Y209581I-3502J-1D01*
G03Y209419I183J-81D01*
G02X1178002Y208000I-3202J-1418D01*
G02X1177702Y206581I-3502J-1D01*
G03Y206419I183J-81D01*
G02X1178002Y205000I-3202J-1418D01*
G02X1174500Y201498I-3502J0D01*
G02X1173081Y201798I-1J3502D01*
G03X1172919I-81J-183D01*
G02X1171500Y201498I-1418J3202D01*
G02X1167998Y205000I0J3502D01*
G02X1168298Y206419I3502J1D01*
G03Y206581I-183J81D01*
G02X1167998Y208000I3202J1418D01*
G02X1168298Y209419I3502J1D01*
G03Y209581I-183J81D01*
G37*
G36*
G01X149247Y224908D02*
G02X148832Y226563I3087J1654D01*
G02X149247Y228218I3502J1D01*
G03Y228408I-176J95D01*
G02X148832Y230063I3087J1654D01*
G02X152065Y233555I3502J0D01*
G03X152211Y233636I-15J200D01*
G02X155034Y235066I2824J-2073D01*
G02X158536Y231563I-1J-3503D01*
G02X158121Y229908I-3502J-1D01*
G03Y229718I176J-95D01*
G02X158536Y228063I-3087J-1654D01*
G02X158121Y226408I-3502J-1D01*
G03Y226218I176J-95D01*
G02X158536Y224563I-3087J-1654D01*
G02X155303Y221071I-3502J0D01*
G03X155157Y220990I15J-200D01*
G02X154140Y220062I-2823J2073D01*
G03X154048Y219846I103J-171D01*
G02X154136Y219063I-3414J-780D01*
G02X147132I-3502J0D01*
G02X148828Y222064I3503J0D01*
G03X148920Y222280I-103J171D01*
G02X148832Y223063I3414J780D01*
G02X149247Y224718I3502J1D01*
G03Y224908I-176J95D01*
G37*
G36*
G01X1064581Y261202D02*
G02X1066000Y261502I1418J-3202D01*
G02X1067419Y261202I1J-3502D01*
G03X1067581I81J183D01*
G02X1069000Y261502I1418J-3202D01*
G02X1070419Y261202I1J-3502D01*
G03X1070581I81J183D01*
G02X1072000Y261502I1418J-3202D01*
G02X1075502Y258000I0J-3502D01*
G02X1075202Y256581I-3502J-1D01*
G03Y256419I183J-81D01*
G02X1075502Y255000I-3202J-1418D01*
G02X1072000Y251498I-3502J0D01*
G02X1070581Y251798I-1J3502D01*
G03X1070419I-81J-183D01*
G02X1069611Y251551I-1420J3202D01*
G03X1069449Y251389I35J-197D01*
G02X1069202Y250581I-3449J612D01*
G03Y250419I183J-81D01*
G02X1069449Y249611I-3202J-1420D01*
G03X1069611Y249449I197J35D01*
G02X1070419Y249202I-612J-3449D01*
G03X1070581I81J183D01*
G02X1072000Y249502I1418J-3202D01*
G02X1075502Y246000I0J-3502D01*
G02X1075202Y244581I-3502J-1D01*
G03Y244419I183J-81D01*
G02X1075502Y243000I-3202J-1418D01*
G02X1072000Y239498I-3502J0D01*
G02X1070581Y239798I-1J3502D01*
G03X1070419I-81J-183D01*
G02X1069000Y239498I-1418J3202D01*
G02X1067581Y239798I-1J3502D01*
G03X1067419I-81J-183D01*
G02X1066000Y239498I-1418J3202D01*
G02X1064581Y239798I-1J3502D01*
G03X1064419I-81J-183D01*
G02X1063000Y239498I-1418J3202D01*
G02X1061581Y239798I-1J3502D01*
G03X1061419I-81J-183D01*
G02X1060000Y239498I-1418J3202D01*
G02X1056498Y243000I0J3502D01*
G02X1056798Y244419I3502J1D01*
G03Y244581I-183J81D01*
G02X1056498Y246000I3202J1418D01*
G02X1056798Y247419I3502J1D01*
G03Y247581I-183J81D01*
G02X1056498Y249000I3202J1418D01*
G02X1056798Y250419I3502J1D01*
G03Y250581I-183J81D01*
G02X1056498Y252000I3202J1418D01*
G02X1056798Y253419I3502J1D01*
G03Y253581I-183J81D01*
G02X1056498Y255000I3202J1418D01*
G02X1056798Y256419I3502J1D01*
G03Y256581I-183J81D01*
G02X1056498Y258000I3202J1418D01*
G02X1060000Y261502I3502J0D01*
G02X1061419Y261202I1J-3502D01*
G03X1061581I81J183D01*
G02X1063000Y261502I1418J-3202D01*
G02X1064419Y261202I1J-3502D01*
G03X1064581I81J183D01*
G37*
G36*
G01X105398Y257141D02*
G02X105098Y258560I3202J1418D01*
G02X105398Y259979I3502J1D01*
G03Y260141I-183J81D01*
G02X105098Y261560I3202J1418D01*
G02X108600Y265062I3502J0D01*
G02X110019Y264762I1J-3502D01*
G03X110181I81J183D01*
G02X111600Y265062I1418J-3202D01*
G02X115102Y261560I0J-3502D01*
G02X114802Y260141I-3502J-1D01*
G03Y259979I183J-81D01*
G02X115102Y258560I-3202J-1418D01*
G02X114802Y257141I-3502J-1D01*
G03Y256979I183J-81D01*
G02X115102Y255560I-3202J-1418D01*
G02X111600Y252058I-3502J0D01*
G02X110181Y252358I-1J3502D01*
G03X110019I-81J-183D01*
G02X108600Y252058I-1418J3202D01*
G02X105098Y255560I0J3502D01*
G02X105398Y256979I3502J1D01*
G03Y257141I-183J81D01*
G37*
G36*
G01X43554Y281934D02*
X44006D01*
X44098Y281986D01*
X44125Y282032D01*
G02X48780Y284694I4656J-2741D01*
G02X54182Y279291I-1J-5403D01*
G02X53113Y276064I-5402J-1D01*
G03Y275825I160J-119D01*
G02X54182Y272598I-4333J-3226D01*
G02X48780Y267196I-5402J0D01*
G02X44125Y269857I0J5402D01*
G01X44098Y269903D01*
X44006Y269955D01*
X43554D01*
X43462Y269903D01*
X43435Y269857D01*
G02X38780Y267196I-4655J2741D01*
G02X33378Y272598I0J5402D01*
G02X34447Y275825I5402J1D01*
G03Y276064I-160J120D01*
G02X33378Y279291I4333J3226D01*
G02X38780Y284694I5402J1D01*
G02X43435Y282032I-1J-5403D01*
G01X43462Y281986D01*
X43554Y281934D01*
G37*
G36*
G01X561243Y272218D02*
X561401Y272604D01*
X561394Y272697D01*
X561369Y272738D01*
G02X560128Y277204I7411J4465D01*
G02X568780Y285856I8652J0D01*
G02X575949Y282049I1J-8652D01*
G01X575977Y282008D01*
X576064Y281961D01*
X576496D01*
X576583Y282008D01*
X576611Y282049D01*
G02X583780Y285856I7168J-4845D01*
G02Y268552I0J-8652D01*
G02X576611Y272359I-1J8652D01*
G01X576583Y272400D01*
X576496Y272447D01*
X576064D01*
X575977Y272400D01*
X575949Y272359D01*
G02X568780Y268552I-7168J4845D01*
G02X567856Y268601I-4J8652D01*
G01X567808Y268606D01*
X567721Y268574D01*
X567437Y268268D01*
X567411Y268178D01*
X567420Y268131D01*
G02X567504Y267204I-5018J-922D01*
G02X557300I-5102J0D01*
G02X561126Y272144I5102J0D01*
G01X561173Y272157D01*
X561243Y272218D01*
G37*
G36*
G01X718724D02*
X718882Y272604D01*
X718875Y272697D01*
X718850Y272738D01*
G02X717608Y277204I7411J4467D01*
G02X726261Y285856I8653J-1D01*
G02X733430Y282049I1J-8652D01*
G01X733458Y282008D01*
X733545Y281961D01*
X733977D01*
X734064Y282008D01*
X734092Y282049D01*
G02X741261Y285856I7168J-4845D01*
G02Y268552I0J-8652D01*
G02X734092Y272359I-1J8652D01*
G01X734064Y272400D01*
X733977Y272447D01*
X733545D01*
X733458Y272400D01*
X733430Y272359D01*
G02X726261Y268552I-7168J4845D01*
G02X725337Y268601I-4J8652D01*
G01X725289Y268606D01*
X725202Y268574D01*
X724918Y268268D01*
X724892Y268178D01*
X724901Y268131D01*
G02X724986Y267204I-5018J-928D01*
G02X714780I-5103J0D01*
G02X718607Y272144I5102J0D01*
G01X718654Y272157D01*
X718724Y272218D01*
G37*
G36*
G01X274082Y284635D02*
G02X277219Y286580I3137J-1557D01*
G02X279111Y286026I2J-3502D01*
G03X279327I108J168D01*
G02X281219Y286580I1890J-2948D01*
G02X283111Y286026I2J-3502D01*
G03X283327I108J168D01*
G02X285219Y286580I1890J-2948D01*
G02X288722Y283078I1J-3502D01*
G02X288167Y281186I-3502J0D01*
G03Y280970I168J-108D01*
G02Y277186I-2947J-1892D01*
G03Y276970I168J-108D01*
G02Y273186I-2947J-1892D01*
G03Y272970I168J-108D01*
G02X288722Y271078I-2947J-1892D01*
G02X285219Y267576I-3503J1D01*
G02X283327Y268130I-2J3502D01*
G03X283111I-108J-168D01*
G02X281219Y267576I-1890J2948D01*
G02X279327Y268130I-2J3502D01*
G03X279111I-108J-168D01*
G02X277219Y267576I-1890J2948D01*
G02X274001Y269696I0J3502D01*
G01X273983Y269736D01*
X273919Y269795D01*
X273544Y269911D01*
X273458Y269900D01*
X273421Y269877D01*
G02X268819Y268552I-4601J7327D01*
G02X261650Y272359I-1J8652D01*
G01X261622Y272400D01*
X261535Y272447D01*
X261103D01*
X261016Y272400D01*
X260988Y272359D01*
G02X253819Y268552I-7168J4845D01*
G02X252895Y268601I-4J8652D01*
G01X252847Y268606D01*
X252760Y268574D01*
X252476Y268268D01*
X252450Y268178D01*
X252459Y268131D01*
G02X252544Y267204I-5018J-928D01*
G02X242338I-5103J0D01*
G02X246165Y272144I5102J0D01*
G01X246212Y272157D01*
X246282Y272218D01*
X246440Y272604D01*
X246433Y272697D01*
X246408Y272738D01*
G02X245166Y277204I7411J4467D01*
G02X253819Y285856I8653J-1D01*
G02X260988Y282049I1J-8652D01*
G01X261016Y282008D01*
X261103Y281961D01*
X261535D01*
X261622Y282008D01*
X261650Y282049D01*
G02X268819Y285856I7168J-4845D01*
G02X273507Y284477I2J-8652D01*
G01X273543Y284453D01*
X273626Y284440D01*
X273998Y284543D01*
X274062Y284596D01*
X274082Y284635D01*
G37*
G36*
G01X431368Y284755D02*
G02X434499Y286688I3131J-1569D01*
G02X436391Y286134I2J-3502D01*
G03X436607I108J168D01*
G02X438499Y286688I1890J-2948D01*
G02X440391Y286134I2J-3502D01*
G03X440607I108J168D01*
G02X442499Y286688I1890J-2948D01*
G02X446002Y283186I1J-3502D01*
G02X445447Y281294I-3502J0D01*
G03Y281078I168J-108D01*
G02Y277294I-2947J-1892D01*
G03Y277078I168J-108D01*
G02Y273294I-2947J-1892D01*
G03Y273078I168J-108D01*
G02X446002Y271186I-2947J-1892D01*
G02X442499Y267684I-3503J1D01*
G02X440607Y268238I-2J3502D01*
G03X440391I-108J-168D01*
G02X438499Y267684I-1890J2948D01*
G02X436607Y268238I-2J3502D01*
G03X436391I-108J-168D01*
G02X434499Y267684I-1890J2948D01*
G02X431355Y269642I0J3503D01*
G01X431337Y269680D01*
X431272Y269734D01*
X430908Y269840D01*
X430825Y269829D01*
X430789Y269807D01*
G02X426299Y268552I-4488J7398D01*
G02X419130Y272359I-1J8652D01*
G01X419102Y272400D01*
X419015Y272447D01*
X418583D01*
X418496Y272400D01*
X418468Y272359D01*
G02X411299Y268552I-7168J4845D01*
G02X410375Y268601I-4J8652D01*
G01X410327Y268606D01*
X410240Y268574D01*
X409956Y268268D01*
X409930Y268178D01*
X409939Y268131D01*
G02X410024Y267204I-5018J-928D01*
G02X399818I-5103J0D01*
G02X403645Y272144I5102J0D01*
G01X403692Y272157D01*
X403762Y272218D01*
X403920Y272604D01*
X403913Y272697D01*
X403888Y272738D01*
G02X402646Y277204I7411J4467D01*
G02X411299Y285856I8653J-1D01*
G02X418468Y282049I1J-8652D01*
G01X418496Y282008D01*
X418583Y281961D01*
X419015D01*
X419102Y282008D01*
X419130Y282049D01*
G02X426299Y285856I7168J-4845D01*
G02X430802Y284593I2J-8652D01*
G01X430838Y284570D01*
X430920Y284559D01*
X431285Y284664D01*
X431348Y284717D01*
X431368Y284755D01*
G37*
G36*
G01X43435Y289857D02*
G02X38780Y287196I-4655J2741D01*
G02X33378Y292598I0J5402D01*
G02X34447Y295825I5402J1D01*
G03Y296064I-160J120D01*
G02X33378Y299291I4333J3226D01*
G02X38780Y304694I5402J1D01*
G02X43435Y302032I-1J-5403D01*
G01X43462Y301986D01*
X43554Y301934D01*
X44006D01*
X44098Y301986D01*
X44125Y302032D01*
G02X48780Y304694I4656J-2741D01*
G02X54182Y299291I-1J-5403D01*
G02X53113Y296064I-5402J-1D01*
G03Y295825I160J-119D01*
G02X54182Y292598I-4333J-3226D01*
G02X48780Y287196I-5402J0D01*
G02X44125Y289857I0J5402D01*
G01X44098Y289903D01*
X44006Y289955D01*
X43554D01*
X43462Y289903D01*
X43435Y289857D01*
G37*
G36*
G01X1064581Y308702D02*
G02X1066000Y309002I1418J-3202D01*
G02X1067419Y308702I1J-3502D01*
G03X1067581I81J183D01*
G02X1069000Y309002I1418J-3202D01*
G02X1070419Y308702I1J-3502D01*
G03X1070581I81J183D01*
G02X1072000Y309002I1418J-3202D01*
G02X1075502Y305500I0J-3502D01*
G02X1075202Y304081I-3502J-1D01*
G03Y303919I183J-81D01*
G02X1075502Y302500I-3202J-1418D01*
G02X1072000Y298998I-3502J0D01*
G02X1070581Y299298I-1J3502D01*
G03X1070419I-81J-183D01*
G02X1069611Y299051I-1420J3202D01*
G03X1069449Y298889I35J-197D01*
G02X1069202Y298081I-3449J612D01*
G03Y297919I183J-81D01*
G02X1069449Y297111I-3202J-1420D01*
G03X1069611Y296949I197J35D01*
G02X1070419Y296702I-612J-3449D01*
G03X1070581I81J183D01*
G02X1072000Y297002I1418J-3202D01*
G02X1075502Y293500I0J-3502D01*
G02X1075202Y292081I-3502J-1D01*
G03Y291919I183J-81D01*
G02X1075502Y290500I-3202J-1418D01*
G02X1072000Y286998I-3502J0D01*
G02X1070581Y287298I-1J3502D01*
G03X1070419I-81J-183D01*
G02X1069000Y286998I-1418J3202D01*
G02X1067581Y287298I-1J3502D01*
G03X1067419I-81J-183D01*
G02X1066000Y286998I-1418J3202D01*
G02X1064581Y287298I-1J3502D01*
G03X1064419I-81J-183D01*
G02X1063000Y286998I-1418J3202D01*
G02X1061581Y287298I-1J3502D01*
G03X1061419I-81J-183D01*
G02X1060000Y286998I-1418J3202D01*
G02X1056498Y290500I0J3502D01*
G02X1056798Y291919I3502J1D01*
G03Y292081I-183J81D01*
G02X1056498Y293500I3202J1418D01*
G02X1056798Y294919I3502J1D01*
G03Y295081I-183J81D01*
G02X1056498Y296500I3202J1418D01*
G02X1056798Y297919I3502J1D01*
G03Y298081I-183J81D01*
G02X1056498Y299500I3202J1418D01*
G02X1056798Y300919I3502J1D01*
G03Y301081I-183J81D01*
G02X1056498Y302500I3202J1418D01*
G02X1056798Y303919I3502J1D01*
G03Y304081I-183J81D01*
G02X1056498Y305500I3202J1418D01*
G02X1060000Y309002I3502J0D01*
G02X1061419Y308702I1J-3502D01*
G03X1061581I81J183D01*
G02X1063000Y309002I1418J-3202D01*
G02X1064419Y308702I1J-3502D01*
G03X1064581I81J183D01*
G37*
G36*
G01X43781Y349915D02*
G02X48780Y354726I4999J-192D01*
G02X53782Y349724I0J-5002D01*
G02X48971Y344725I-5003J0D01*
G03X48779Y344533I8J-200D01*
G02X43780Y339722I-4999J192D01*
G02X38778Y344724I0J5002D01*
G02X43589Y349723I5003J0D01*
G03X43781Y349915I-8J200D01*
G37*
G36*
G01X1059200Y356470D02*
X1059308Y356917D01*
X1059276Y357021D01*
X1059236Y357058D01*
G02X1058098Y359642I2365J2584D01*
G02X1065102I3502J0D01*
G02X1063920Y357018I-3502J-1D01*
G01X1063879Y356982D01*
X1063845Y356880D01*
X1063940Y356433D01*
X1064011Y356354D01*
X1064063Y356337D01*
G02X1064419Y356202I-1062J-3337D01*
G03X1064581I81J183D01*
G02X1066000Y356502I1418J-3202D01*
G02X1067419Y356202I1J-3502D01*
G03X1067581I81J183D01*
G02X1069000Y356502I1418J-3202D01*
G02X1070419Y356202I1J-3502D01*
G03X1070581I81J183D01*
G02X1072000Y356502I1418J-3202D01*
G02X1075502Y353000I0J-3502D01*
G02X1075202Y351581I-3502J-1D01*
G03Y351419I183J-81D01*
G02X1075502Y350000I-3202J-1418D01*
G02X1072000Y346498I-3502J0D01*
G02X1070581Y346798I-1J3502D01*
G03X1070419I-81J-183D01*
G02X1069611Y346551I-1420J3202D01*
G03X1069449Y346389I35J-197D01*
G02X1069202Y345581I-3449J612D01*
G03Y345419I183J-81D01*
G02X1069449Y344611I-3202J-1420D01*
G03X1069611Y344449I197J35D01*
G02X1070419Y344202I-612J-3449D01*
G03X1070581I81J183D01*
G02X1072000Y344502I1418J-3202D01*
G02X1075502Y341000I0J-3502D01*
G02X1075202Y339581I-3502J-1D01*
G03Y339419I183J-81D01*
G02X1075502Y338000I-3202J-1418D01*
G02X1072000Y334498I-3502J0D01*
G02X1070581Y334798I-1J3502D01*
G03X1070419I-81J-183D01*
G02X1069000Y334498I-1418J3202D01*
G02X1067581Y334798I-1J3502D01*
G03X1067419I-81J-183D01*
G02X1066000Y334498I-1418J3202D01*
G02X1064581Y334798I-1J3502D01*
G03X1064419I-81J-183D01*
G02X1063000Y334498I-1418J3202D01*
G02X1061581Y334798I-1J3502D01*
G03X1061419I-81J-183D01*
G02X1060000Y334498I-1418J3202D01*
G02X1056498Y338000I0J3502D01*
G02X1056798Y339419I3502J1D01*
G03Y339581I-183J81D01*
G02X1056498Y341000I3202J1418D01*
G02X1056798Y342419I3502J1D01*
G03Y342581I-183J81D01*
G02X1056498Y344000I3202J1418D01*
G02X1056798Y345419I3502J1D01*
G03Y345581I-183J81D01*
G02X1056498Y347000I3202J1418D01*
G02X1056798Y348419I3502J1D01*
G03Y348581I-183J81D01*
G02X1056498Y350000I3202J1418D01*
G02X1056798Y351419I3502J1D01*
G03Y351581I-183J81D01*
G02X1056498Y353000I3202J1418D01*
G02X1059072Y356377I3502J0D01*
G01X1059125Y356392D01*
X1059200Y356470D01*
G37*
G36*
G01X946985Y388121D02*
X947372D01*
X947450Y388156D01*
X947479Y388189D01*
G02X950110Y389380I2632J-2312D01*
G02X951529Y389079I-2J-3503D01*
G03X951691I81J183D01*
G02X953110Y389380I1421J-3202D01*
G02Y382374I0J-3503D01*
G02X951691Y382675I2J3503D01*
G03X951529I-81J-183D01*
G02X950110Y382374I-1421J3202D01*
G02X947479Y383565I1J3503D01*
G01X947450Y383598D01*
X947372Y383633D01*
X946985D01*
X946907Y383598D01*
X946878Y383565D01*
G02X944247Y382374I-2632J2312D01*
G02X942828Y382675I2J3503D01*
G03X942666I-81J-183D01*
G02X941247Y382374I-1421J3202D01*
G02X938162Y384219I0J3502D01*
G01X938135Y384269D01*
X938039Y384325D01*
X937571Y384318D01*
X937477Y384259D01*
X937452Y384208D01*
G02X934317Y382268I-3135J1563D01*
G02X932898Y382569I2J3503D01*
G03X932736I-81J-183D01*
G02X931317Y382268I-1421J3202D01*
G02X928686Y383459I1J3503D01*
G01X928657Y383492D01*
X928579Y383527D01*
X928192D01*
X928114Y383492D01*
X928085Y383459D01*
G02X925454Y382268I-2632J2312D01*
G02X924035Y382569I2J3503D01*
G03X923873I-81J-183D01*
G02X922454Y382268I-1421J3202D01*
G02X919320Y384207I0J3502D01*
G01X919295Y384258D01*
X919201Y384317D01*
X918732Y384324D01*
X918637Y384268D01*
X918610Y384218D01*
G02X915525Y382374I-3085J1659D01*
G02X914106Y382675I2J3503D01*
G03X913944I-81J-183D01*
G02X912525Y382374I-1421J3202D01*
G02X909894Y383565I1J3503D01*
G01X909865Y383598D01*
X909787Y383633D01*
X909400D01*
X909322Y383598D01*
X909293Y383565D01*
G02X906662Y382374I-2632J2312D01*
G02X905243Y382675I2J3503D01*
G03X905081I-81J-183D01*
G02X903662Y382374I-1421J3202D01*
G02Y389380I0J3503D01*
G02X905081Y389079I-2J-3503D01*
G03X905243I81J183D01*
G02X906662Y389380I1421J-3202D01*
G02X909293Y388189I-1J-3503D01*
G01X909322Y388156D01*
X909400Y388121D01*
X909787D01*
X909865Y388156D01*
X909894Y388189D01*
G02X912525Y389380I2632J-2312D01*
G02X913944Y389079I-2J-3503D01*
G03X914106I81J183D01*
G02X915525Y389380I1421J-3202D01*
G02X918659Y387441I0J-3502D01*
G01X918684Y387390D01*
X918778Y387331D01*
X919247Y387324D01*
X919342Y387380D01*
X919369Y387430D01*
G02X922454Y389274I3085J-1659D01*
G02X923873Y388973I-2J-3503D01*
G03X924035I81J183D01*
G02X925454Y389274I1421J-3202D01*
G02X928085Y388083I-1J-3503D01*
G01X928114Y388050D01*
X928192Y388015D01*
X928579D01*
X928657Y388050D01*
X928686Y388083D01*
G02X931317Y389274I2632J-2312D01*
G02X932736Y388973I-2J-3503D01*
G03X932898I81J183D01*
G02X934317Y389274I1421J-3202D01*
G02X937402Y387429I0J-3502D01*
G01X937429Y387379D01*
X937525Y387323D01*
X937993Y387330D01*
X938087Y387389D01*
X938112Y387440D01*
G02X941247Y389380I3135J-1563D01*
G02X942666Y389079I-2J-3503D01*
G03X942828I81J183D01*
G02X944247Y389380I1421J-3202D01*
G02X946878Y388189I-1J-3503D01*
G01X946907Y388156D01*
X946985Y388121D01*
G37*
G36*
G01X853128Y388122D02*
X853515D01*
X853593Y388157D01*
X853622Y388190D01*
G02X856253Y389380I2630J-2312D01*
G02X857672Y389080I1J-3502D01*
G03X857834I81J183D01*
G02X859253Y389380I1418J-3202D01*
G02X862110Y387903I0J-3502D01*
G01X862138Y387864D01*
X862222Y387820D01*
X862641Y387813D01*
X862726Y387854D01*
X862755Y387892D01*
G02X865542Y389274I2788J-2121D01*
G02X866961Y388973I-2J-3503D01*
G03X867123I81J183D01*
G02X868542Y389274I1421J-3202D01*
G02X871173Y388083I-1J-3503D01*
G01X871202Y388050D01*
X871280Y388015D01*
X871667D01*
X871745Y388050D01*
X871774Y388083D01*
G02X874405Y389274I2632J-2312D01*
G02X875824Y388973I-2J-3503D01*
G03X875986I81J183D01*
G02X877405Y389274I1421J-3202D01*
G02X880467Y387472I0J-3503D01*
G03X880642Y387369I175J97D01*
G01X880991D01*
G03X881166Y387472I0J200D01*
G02X884228Y389274I3062J-1701D01*
G02X885647Y388973I-2J-3503D01*
G03X885809I81J183D01*
G02X887228Y389274I1421J-3202D01*
G02X889859Y388083I-1J-3503D01*
G01X889888Y388050D01*
X889966Y388015D01*
X890353D01*
X890431Y388050D01*
X890460Y388083D01*
G02X893091Y389274I2632J-2312D01*
G02X894510Y388973I-2J-3503D01*
G03X894672I81J183D01*
G02X896091Y389274I1421J-3202D01*
G02Y382268I0J-3503D01*
G02X894672Y382569I2J3503D01*
G03X894510I-81J-183D01*
G02X893091Y382268I-1421J3202D01*
G02X890460Y383459I1J3503D01*
G01X890431Y383492D01*
X890353Y383527D01*
X889966D01*
X889888Y383492D01*
X889859Y383459D01*
G02X887228Y382268I-2632J2312D01*
G02X885809Y382569I2J3503D01*
G03X885647I-81J-183D01*
G02X884228Y382268I-1421J3202D01*
G02X881166Y384070I0J3503D01*
G03X880991Y384173I-175J-97D01*
G01X880642D01*
G03X880467Y384070I0J-200D01*
G02X877405Y382268I-3062J1701D01*
G02X875986Y382569I2J3503D01*
G03X875824I-81J-183D01*
G02X874405Y382268I-1421J3202D01*
G02X871774Y383459I1J3503D01*
G01X871745Y383492D01*
X871667Y383527D01*
X871280D01*
X871202Y383492D01*
X871173Y383459D01*
G02X868542Y382268I-2632J2312D01*
G02X867123Y382569I2J3503D01*
G03X866961I-81J-183D01*
G02X865542Y382268I-1421J3202D01*
G02X862685Y383746I1J3502D01*
G01X862657Y383785D01*
X862573Y383829D01*
X862154Y383836D01*
X862069Y383795D01*
X862040Y383757D01*
G02X859253Y382376I-2787J2122D01*
G02X857834Y382676I-1J3502D01*
G03X857672I-81J-183D01*
G02X856253Y382376I-1418J3202D01*
G02X853622Y383566I-1J3502D01*
G01X853593Y383599D01*
X853515Y383634D01*
X853128D01*
X853050Y383599D01*
X853021Y383566D01*
G02X850390Y382376I-2630J2312D01*
G02X848971Y382676I-1J3502D01*
G03X848809I-81J-183D01*
G02X847390Y382376I-1418J3202D01*
G02Y389380I0J3502D01*
G02X848809Y389080I1J-3502D01*
G03X848971I81J183D01*
G02X850390Y389380I1418J-3202D01*
G02X853021Y388190I1J-3502D01*
G01X853050Y388157D01*
X853128Y388122D01*
G37*
G36*
G01X1071582Y404036D02*
X1071738Y404469D01*
X1071718Y404575D01*
X1071682Y404617D01*
G02X1070814Y406925I2634J2308D01*
G02X1077818I3502J0D01*
G02X1074872Y403467I-3502J0D01*
G01X1074817Y403458D01*
X1074734Y403389D01*
X1074578Y402956D01*
X1074598Y402850D01*
X1074634Y402808D01*
G02X1075502Y400500I-2634J-2308D01*
G02X1075202Y399081I-3502J-1D01*
G03Y398919I183J-81D01*
G02X1075502Y397500I-3202J-1418D01*
G02X1072000Y393998I-3502J0D01*
G02X1070581Y394298I-1J3502D01*
G03X1070419I-81J-183D01*
G02X1069611Y394051I-1420J3202D01*
G03X1069449Y393889I35J-197D01*
G02X1069202Y393081I-3449J612D01*
G03Y392919I183J-81D01*
G02X1069449Y392111I-3202J-1420D01*
G03X1069611Y391949I197J35D01*
G02X1070419Y391702I-612J-3449D01*
G03X1070581I81J183D01*
G02X1072000Y392002I1418J-3202D01*
G02X1075502Y388500I0J-3502D01*
G02X1075202Y387081I-3502J-1D01*
G03Y386919I183J-81D01*
G02X1075502Y385500I-3202J-1418D01*
G02X1072000Y381998I-3502J0D01*
G02X1070581Y382298I-1J3502D01*
G03X1070419I-81J-183D01*
G02X1069000Y381998I-1418J3202D01*
G02X1067581Y382298I-1J3502D01*
G03X1067419I-81J-183D01*
G02X1066000Y381998I-1418J3202D01*
G02X1064581Y382298I-1J3502D01*
G03X1064419I-81J-183D01*
G02X1063000Y381998I-1418J3202D01*
G02X1061581Y382298I-1J3502D01*
G03X1061419I-81J-183D01*
G02X1060000Y381998I-1418J3202D01*
G02X1056498Y385500I0J3502D01*
G02X1056798Y386919I3502J1D01*
G03Y387081I-183J81D01*
G02X1056498Y388500I3202J1418D01*
G02X1056798Y389919I3502J1D01*
G03Y390081I-183J81D01*
G02X1056498Y391500I3202J1418D01*
G02X1056798Y392919I3502J1D01*
G03Y393081I-183J81D01*
G02X1056498Y394500I3202J1418D01*
G02X1056798Y395919I3502J1D01*
G03Y396081I-183J81D01*
G02X1056498Y397500I3202J1418D01*
G02X1056798Y398919I3502J1D01*
G03Y399081I-183J81D01*
G02X1056498Y400500I3202J1418D01*
G02X1060000Y404002I3502J0D01*
G02X1061419Y403702I1J-3502D01*
G03X1061581I81J183D01*
G02X1063000Y404002I1418J-3202D01*
G02X1064419Y403702I1J-3502D01*
G03X1064581I81J183D01*
G02X1066000Y404002I1418J-3202D01*
G02X1067419Y403702I1J-3502D01*
G03X1067581I81J183D01*
G02X1069000Y404002I1418J-3202D01*
G02X1070419Y403702I1J-3502D01*
G03X1070581I81J183D01*
G02X1071444Y403958I1419J-3202D01*
G01X1071499Y403967D01*
X1071582Y404036D01*
G37*
G36*
G01X806904Y420118D02*
G02X808323Y420418I1418J-3202D01*
G02X809742Y420118I1J-3502D01*
G03X809904I81J183D01*
G02X811323Y420418I1418J-3202D01*
G02X812742Y420118I1J-3502D01*
G03X812904I81J183D01*
G02X814323Y420418I1418J-3202D01*
G02X815723Y420126I0J-3502D01*
G03X815876Y420123I80J184D01*
G02X817153Y420364I1277J-3261D01*
G02X820656Y416862I1J-3502D01*
G02X820355Y415443I-3503J2D01*
G03Y415281I183J-81D01*
G02X820656Y413862I-3202J-1421D01*
G02X820402Y412554I-3503J2D01*
G03Y412404I186J-75D01*
G02X820656Y411096I-3249J-1310D01*
G02X820355Y409677I-3503J2D01*
G03Y409515I183J-81D01*
G02X820656Y408096I-3202J-1421D01*
G02X820355Y406677I-3503J2D01*
G03Y406515I183J-81D01*
G02X820656Y405096I-3202J-1421D01*
G02X817153Y401594I-3503J1D01*
G02X815753Y401886I0J3502D01*
G03X815600Y401889I-80J-184D01*
G02X814323Y401648I-1277J3261D01*
G02X812904Y401948I-1J3502D01*
G03X812742I-81J-183D01*
G02X811323Y401648I-1418J3202D01*
G02X809904Y401948I-1J3502D01*
G03X809742I-81J-183D01*
G02X808323Y401648I-1418J3202D01*
G02X806904Y401948I-1J3502D01*
G03X806742I-81J-183D01*
G02X805323Y401648I-1418J3202D01*
G02X803904Y401948I-1J3502D01*
G03X803742I-81J-183D01*
G02X802323Y401648I-1418J3202D01*
G02X800904Y401948I-1J3502D01*
G03X800742I-81J-183D01*
G02X799323Y401648I-1418J3202D01*
G02X798098Y401869I-1J3502D01*
G03X797951Y401866I-70J-188D01*
G02X796600Y401594I-1353J3231D01*
G02X793098Y405097I1J3503D01*
G02X793398Y406516I3502J1D01*
G03Y406678I-183J81D01*
G02X793098Y408097I3202J1418D01*
G02X793398Y409516I3502J1D01*
G03Y409678I-183J81D01*
G02X793098Y411097I3202J1418D01*
G02X793351Y412405I3502J1D01*
G03Y412555I-186J75D01*
G02X793098Y413863I3249J1307D01*
G02X793398Y415282I3502J1D01*
G03Y415444I-183J81D01*
G02X793098Y416863I3202J1418D01*
G02X796600Y420366I3502J1D01*
G02X797825Y420144I-2J-3503D01*
G03X797972Y420147I70J188D01*
G02X799323Y420418I1351J-3232D01*
G02X800742Y420118I1J-3502D01*
G03X800904I81J183D01*
G02X802323Y420418I1418J-3202D01*
G02X803742Y420118I1J-3502D01*
G03X803904I81J183D01*
G02X805323Y420418I1418J-3202D01*
G02X806742Y420118I1J-3502D01*
G03X806904I81J183D01*
G37*
G36*
G01X863923D02*
G02X865342Y420418I1418J-3202D01*
G02X866761Y420118I1J-3502D01*
G03X866923I81J183D01*
G02X868342Y420418I1418J-3202D01*
G02X869761Y420118I1J-3502D01*
G03X869923I81J183D01*
G02X871342Y420418I1418J-3202D01*
G02X872742Y420126I0J-3502D01*
G03X872895Y420123I80J184D01*
G02X874172Y420364I1277J-3261D01*
G02X877674Y416862I0J-3502D01*
G02X877374Y415443I-3502J-1D01*
G03Y415281I183J-81D01*
G02X877674Y413862I-3202J-1418D01*
G02X877421Y412554I-3502J-1D01*
G03Y412404I186J-75D01*
G02X877674Y411096I-3249J-1307D01*
G02X877374Y409677I-3502J-1D01*
G03Y409515I183J-81D01*
G02X877674Y408096I-3202J-1418D01*
G02X877374Y406677I-3502J-1D01*
G03Y406515I183J-81D01*
G02X877674Y405096I-3202J-1418D01*
G02X874172Y401594I-3502J0D01*
G02X872772Y401886I0J3502D01*
G03X872619Y401889I-80J-184D01*
G02X871342Y401648I-1277J3261D01*
G02X869923Y401948I-1J3502D01*
G03X869761I-81J-183D01*
G02X868342Y401648I-1418J3202D01*
G02X866923Y401948I-1J3502D01*
G03X866761I-81J-183D01*
G02X865342Y401648I-1418J3202D01*
G02X863923Y401948I-1J3502D01*
G03X863761I-81J-183D01*
G02X862342Y401648I-1418J3202D01*
G02X860923Y401948I-1J3502D01*
G03X860761I-81J-183D01*
G02X859342Y401648I-1418J3202D01*
G02X857923Y401948I-1J3502D01*
G03X857761I-81J-183D01*
G02X856342Y401648I-1418J3202D01*
G02X855117Y401869I-1J3502D01*
G03X854970Y401866I-70J-188D01*
G02X853619Y401594I-1353J3231D01*
G02X850116Y405097I0J3503D01*
G02X850417Y406516I3503J-2D01*
G03Y406678I-183J81D01*
G02X850116Y408097I3202J1421D01*
G02X850417Y409516I3503J-2D01*
G03Y409678I-183J81D01*
G02X850116Y411097I3202J1421D01*
G02X850370Y412405I3503J-2D01*
G03Y412555I-186J75D01*
G02X850116Y413863I3249J1310D01*
G02X850417Y415282I3503J-2D01*
G03Y415444I-183J81D01*
G02X850116Y416863I3202J1421D01*
G02X853619Y420366I3503J0D01*
G02X854844Y420144I-2J-3503D01*
G03X854991Y420147I70J188D01*
G02X856342Y420418I1351J-3232D01*
G02X857761Y420118I1J-3502D01*
G03X857923I81J183D01*
G02X859342Y420418I1418J-3202D01*
G02X860761Y420118I1J-3502D01*
G03X860923I81J183D01*
G02X862342Y420418I1418J-3202D01*
G02X863761Y420118I1J-3502D01*
G03X863923I81J183D01*
G37*
G36*
G01X112520Y422234D02*
G02X112198Y423700I3180J1467D01*
G02X112498Y425119I3502J1D01*
G03Y425281I-182J81D01*
G02X112198Y426700I3202J1418D01*
G02X115700Y430202I3502J0D01*
G02X117576Y429657I0J-3501D01*
G03X117782Y429651I108J169D01*
G02X119500Y430102I1719J-3051D01*
G02X121155Y429686I0J-3502D01*
G03X121345I95J176D01*
G02X123000Y430102I1655J-3086D01*
G02X126502Y426600I0J-3502D01*
G02X126202Y425181I-3502J-1D01*
G03Y425019I182J-81D01*
G02X126502Y423600I-3202J-1418D01*
G02X126181Y422134I-3502J-1D01*
G03Y421967I181J-84D01*
G02X126502Y420500I-3181J-1465D01*
G02X126202Y419081I-3502J-1D01*
G03Y418919I183J-81D01*
G02X126502Y417500I-3202J-1418D01*
G02X126202Y416081I-3502J-1D01*
G03Y415919I183J-81D01*
G02X126502Y414500I-3202J-1418D01*
G02X126202Y413081I-3502J-1D01*
G03Y412919I183J-81D01*
G02X126502Y411500I-3202J-1418D01*
G02X126202Y410081I-3502J-1D01*
G03Y409919I183J-81D01*
G02X126502Y408500I-3202J-1418D01*
G02X123000Y404998I-3502J0D01*
G02X121345Y405413I-1J3502D01*
G03X121155I-95J-176D01*
G02X119500Y404998I-1654J3087D01*
G02X117623Y405543I-1J3502D01*
G03X117418Y405548I-107J-169D01*
G02X115700Y405098I-1717J3052D01*
G02X112198Y408600I0J3502D01*
G02X112498Y410019I3502J1D01*
G03Y410181I-182J81D01*
G02X112198Y411600I3202J1418D01*
G02X112498Y413019I3502J1D01*
G03Y413181I-182J81D01*
G02X112198Y414600I3202J1418D01*
G02X112498Y416019I3502J1D01*
G03Y416181I-182J81D01*
G02X112198Y417600I3202J1418D01*
G02X112498Y419019I3502J1D01*
G03Y419181I-182J81D01*
G02X112198Y420600I3202J1418D01*
G02X112520Y422066I3502J-1D01*
G03Y422234I-182J84D01*
G37*
G36*
G01X153598Y425181D02*
G02X153298Y426600I3202J1418D01*
G02X156800Y430102I3502J0D01*
G02X158455Y429686I0J-3502D01*
G03X158645I95J176D01*
G02X160300Y430102I1655J-3086D01*
G02X161867Y429732I0J-3503D01*
G03X162056Y429737I90J179D01*
G02X163800Y430202I1744J-3038D01*
G02X167302Y426700I0J-3502D01*
G02X167002Y425281I-3502J-1D01*
G03Y425119I182J-81D01*
G02X167302Y423700I-3202J-1418D01*
G02X167067Y422438I-3502J-1D01*
G03X167078Y422271I187J-72D01*
G02X167502Y420600I-3078J-1670D01*
G02X167202Y419181I-3502J-1D01*
G03Y419019I182J-81D01*
G02X167502Y417600I-3202J-1418D01*
G02X167202Y416181I-3502J-1D01*
G03Y416019I182J-81D01*
G02X167502Y414600I-3202J-1418D01*
G02X167202Y413181I-3502J-1D01*
G03Y413019I182J-81D01*
G02X167502Y411600I-3202J-1418D01*
G02X167202Y410181I-3502J-1D01*
G03Y410019I182J-81D01*
G02X167502Y408600I-3202J-1418D01*
G02X164000Y405098I-3502J0D01*
G02X162433Y405468I0J3503D01*
G03X162244Y405463I-90J-179D01*
G02X160500Y404998I-1744J3038D01*
G02X158845Y405413I-1J3502D01*
G03X158655I-95J-176D01*
G02X157000Y404998I-1654J3087D01*
G02X153498Y408500I0J3502D01*
G02X153798Y409919I3502J1D01*
G03Y410081I-183J81D01*
G02X153498Y411500I3202J1418D01*
G02X153798Y412919I3502J1D01*
G03Y413081I-183J81D01*
G02X153498Y414500I3202J1418D01*
G02X153798Y415919I3502J1D01*
G03Y416081I-183J81D01*
G02X153498Y417500I3202J1418D01*
G02X153798Y418919I3502J1D01*
G03Y419081I-183J81D01*
G02X153498Y420500I3202J1418D01*
G02X153733Y421762I3502J1D01*
G03X153722Y421930I-187J72D01*
G02X153298Y423600I3077J1670D01*
G02X153598Y425019I3502J1D01*
G03Y425181I-182J81D01*
G37*
G36*
G01X563318Y445297D02*
G02X564500Y445502I1181J-3297D01*
G02Y438498I0J-3502D01*
G02X563318Y438703I-1J3502D01*
G03X563182I-68J-188D01*
G02X562000Y438498I-1181J3297D01*
G02Y445502I0J3502D01*
G02X563182Y445297I1J-3502D01*
G03X563318I68J188D01*
G37*
G36*
G01X1064581Y451202D02*
G02X1066000Y451502I1418J-3202D01*
G02X1067419Y451202I1J-3502D01*
G03X1067581I81J183D01*
G02X1069000Y451502I1418J-3202D01*
G02X1070419Y451202I1J-3502D01*
G03X1070581I81J183D01*
G02X1072000Y451502I1418J-3202D01*
G02X1075502Y448000I0J-3502D01*
G02X1075202Y446581I-3502J-1D01*
G03Y446419I183J-81D01*
G02X1075502Y445000I-3202J-1418D01*
G02X1072000Y441498I-3502J0D01*
G02X1070581Y441798I-1J3502D01*
G03X1070419I-81J-183D01*
G02X1069611Y441551I-1420J3202D01*
G03X1069449Y441389I35J-197D01*
G02X1069202Y440581I-3449J612D01*
G03Y440419I183J-81D01*
G02X1069449Y439611I-3202J-1420D01*
G03X1069611Y439449I197J35D01*
G02X1070419Y439202I-612J-3449D01*
G03X1070581I81J183D01*
G02X1072000Y439502I1418J-3202D01*
G02X1075502Y436000I0J-3502D01*
G02X1075202Y434581I-3502J-1D01*
G03Y434419I183J-81D01*
G02X1075502Y433000I-3202J-1418D01*
G02X1072000Y429498I-3502J0D01*
G02X1070581Y429798I-1J3502D01*
G03X1070419I-81J-183D01*
G02X1069000Y429498I-1418J3202D01*
G02X1067581Y429798I-1J3502D01*
G03X1067419I-81J-183D01*
G02X1066000Y429498I-1418J3202D01*
G02X1064581Y429798I-1J3502D01*
G03X1064419I-81J-183D01*
G02X1063000Y429498I-1418J3202D01*
G02X1061581Y429798I-1J3502D01*
G03X1061419I-81J-183D01*
G02X1060000Y429498I-1418J3202D01*
G02X1056498Y433000I0J3502D01*
G02X1056798Y434419I3502J1D01*
G03Y434581I-183J81D01*
G02X1056498Y436000I3202J1418D01*
G02X1056798Y437419I3502J1D01*
G03Y437581I-183J81D01*
G02X1056498Y439000I3202J1418D01*
G02X1056798Y440419I3502J1D01*
G03Y440581I-183J81D01*
G02X1056498Y442000I3202J1418D01*
G02X1056798Y443419I3502J1D01*
G03Y443581I-183J81D01*
G02X1056498Y445000I3202J1418D01*
G02X1056798Y446419I3502J1D01*
G03Y446581I-183J81D01*
G02X1056498Y448000I3202J1418D01*
G02X1060000Y451502I3502J0D01*
G02X1061419Y451202I1J-3502D01*
G03X1061581I81J183D01*
G02X1063000Y451502I1418J-3202D01*
G02X1064419Y451202I1J-3502D01*
G03X1064581I81J183D01*
G37*
G36*
G01X810290Y489534D02*
G02X811709Y489834I1418J-3202D01*
G02X813128Y489534I1J-3502D01*
G03X813290I81J183D01*
G02X814709Y489834I1418J-3202D01*
G02X816128Y489534I1J-3502D01*
G03X816290I81J183D01*
G02X817709Y489834I1418J-3202D01*
G02X821212Y486332I1J-3502D01*
G02X820920Y484932I-3502J0D01*
G03X820917Y484779I183J-80D01*
G02X821158Y483503I-3262J-1277D01*
G02X820857Y482084I-3503J2D01*
G03Y481922I183J-81D01*
G02X821158Y480503I-3202J-1421D01*
G02X820894Y479170I-3503J1D01*
G03Y479017I185J-76D01*
G02X821158Y477684I-3239J-1334D01*
G02X820857Y476265I-3503J2D01*
G03Y476103I183J-81D01*
G02X821158Y474684I-3202J-1421D01*
G02X817655Y471182I-3503J1D01*
G02X816236Y471482I-1J3502D01*
G03X816074I-81J-183D01*
G02X814655Y471182I-1418J3202D01*
G02X813236Y471482I-1J3502D01*
G03X813074I-81J-183D01*
G02X811655Y471182I-1418J3202D01*
G02X810236Y471482I-1J3502D01*
G03X810074I-81J-183D01*
G02X808655Y471182I-1418J3202D01*
G02X807236Y471482I-1J3502D01*
G03X807074I-81J-183D01*
G02X805655Y471182I-1418J3202D01*
G02X804236Y471482I-1J3502D01*
G03X804074I-81J-183D01*
G02X802655Y471182I-1418J3202D01*
G02X801236Y471482I-1J3502D01*
G03X801074I-81J-183D01*
G02X799655Y471182I-1418J3202D01*
G02X798236Y471482I-1J3502D01*
G03X798074I-81J-183D01*
G02X796655Y471182I-1418J3202D01*
G02X793152Y474684I-1J3502D01*
G02X793453Y476103I3503J-2D01*
G03Y476265I-183J81D01*
G02X793152Y477684I3202J1421D01*
G02X793416Y479017I3503J-1D01*
G03Y479170I-185J77D01*
G02X793152Y480503I3239J1334D01*
G02X793453Y481922I3503J-2D01*
G03Y482084I-183J81D01*
G02X793152Y483503I3202J1421D01*
G02X793444Y484903I3502J0D01*
G03X793447Y485056I-183J80D01*
G02X793206Y486332I3262J1277D01*
G02X796709Y489834I3503J-1D01*
G02X798128Y489534I1J-3502D01*
G03X798290I81J183D01*
G02X799709Y489834I1418J-3202D01*
G02X801128Y489534I1J-3502D01*
G03X801290I81J183D01*
G02X802709Y489834I1418J-3202D01*
G02X804128Y489534I1J-3502D01*
G03X804290I81J183D01*
G02X805709Y489834I1418J-3202D01*
G02X807128Y489534I1J-3502D01*
G03X807290I81J183D01*
G02X808709Y489834I1418J-3202D01*
G02X810128Y489534I1J-3502D01*
G03X810290I81J183D01*
G37*
G36*
G01X866892D02*
G02X868311Y489834I1418J-3202D01*
G02X869730Y489534I1J-3502D01*
G03X869892I81J183D01*
G02X871311Y489834I1418J-3202D01*
G02X872730Y489534I1J-3502D01*
G03X872892I81J183D01*
G02X874311Y489834I1418J-3202D01*
G02X877814Y486332I1J-3502D01*
G02X877522Y484932I-3502J0D01*
G03X877519Y484779I183J-80D01*
G02X877760Y483503I-3262J-1277D01*
G02X877459Y482084I-3503J2D01*
G03Y481922I183J-81D01*
G02X877760Y480503I-3202J-1421D01*
G02X877496Y479170I-3503J1D01*
G03Y479017I185J-76D01*
G02X877760Y477684I-3239J-1334D01*
G02X877459Y476265I-3503J2D01*
G03Y476103I183J-81D01*
G02X877760Y474684I-3202J-1421D01*
G02X874257Y471182I-3503J1D01*
G02X872838Y471482I-1J3502D01*
G03X872676I-81J-183D01*
G02X871257Y471182I-1418J3202D01*
G02X869838Y471482I-1J3502D01*
G03X869676I-81J-183D01*
G02X868257Y471182I-1418J3202D01*
G02X866838Y471482I-1J3502D01*
G03X866676I-81J-183D01*
G02X865257Y471182I-1418J3202D01*
G02X863838Y471482I-1J3502D01*
G03X863676I-81J-183D01*
G02X862257Y471182I-1418J3202D01*
G02X860838Y471482I-1J3502D01*
G03X860676I-81J-183D01*
G02X859257Y471182I-1418J3202D01*
G02X857838Y471482I-1J3502D01*
G03X857676I-81J-183D01*
G02X856257Y471182I-1418J3202D01*
G02X854838Y471482I-1J3502D01*
G03X854676I-81J-183D01*
G02X853257Y471182I-1418J3202D01*
G02X849754Y474684I-1J3502D01*
G02X850055Y476103I3503J-2D01*
G03Y476265I-183J81D01*
G02X849754Y477684I3202J1421D01*
G02X850018Y479017I3503J-1D01*
G03Y479170I-185J77D01*
G02X849754Y480503I3239J1334D01*
G02X850055Y481922I3503J-2D01*
G03Y482084I-183J81D01*
G02X849754Y483503I3202J1421D01*
G02X850046Y484903I3502J0D01*
G03X850049Y485056I-183J80D01*
G02X849808Y486332I3262J1277D01*
G02X853311Y489834I3503J-1D01*
G02X854730Y489534I1J-3502D01*
G03X854892I81J183D01*
G02X856311Y489834I1418J-3202D01*
G02X857730Y489534I1J-3502D01*
G03X857892I81J183D01*
G02X859311Y489834I1418J-3202D01*
G02X860730Y489534I1J-3502D01*
G03X860892I81J183D01*
G02X862311Y489834I1418J-3202D01*
G02X863730Y489534I1J-3502D01*
G03X863892I81J183D01*
G02X865311Y489834I1418J-3202D01*
G02X866730Y489534I1J-3502D01*
G03X866892I81J183D01*
G37*
G36*
G01X68400Y475573D02*
X67972Y475638D01*
X67879Y475606D01*
X67844Y475568D01*
G02Y488842I-7214J6637D01*
G01X67879Y488804D01*
X67972Y488772D01*
X68400Y488837D01*
X68479Y488896D01*
X68500Y488942D01*
G02X82795Y498008I14295J-6737D01*
G02Y466402I0J-15803D01*
G02X68500Y475468I0J15803D01*
G01X68479Y475514D01*
X68400Y475573D01*
G37*
G36*
G01X1064581Y498702D02*
G02X1066000Y499002I1418J-3202D01*
G02X1067419Y498702I1J-3502D01*
G03X1067581I81J183D01*
G02X1069000Y499002I1418J-3202D01*
G02X1070419Y498702I1J-3502D01*
G03X1070581I81J183D01*
G02X1072000Y499002I1418J-3202D01*
G02X1075502Y495500I0J-3502D01*
G02X1075202Y494081I-3502J-1D01*
G03Y493919I183J-81D01*
G02X1075502Y492500I-3202J-1418D01*
G02X1072000Y488998I-3502J0D01*
G02X1070581Y489298I-1J3502D01*
G03X1070419I-81J-183D01*
G02X1069611Y489051I-1420J3202D01*
G03X1069449Y488889I35J-197D01*
G02X1069202Y488081I-3449J612D01*
G03Y487919I183J-81D01*
G02X1069449Y487111I-3202J-1420D01*
G03X1069611Y486949I197J35D01*
G02X1070419Y486702I-612J-3449D01*
G03X1070581I81J183D01*
G02X1072000Y487002I1418J-3202D01*
G02X1075502Y483500I0J-3502D01*
G02X1075202Y482081I-3502J-1D01*
G03Y481919I183J-81D01*
G02X1075502Y480500I-3202J-1418D01*
G02X1072000Y476998I-3502J0D01*
G02X1070581Y477298I-1J3502D01*
G03X1070419I-81J-183D01*
G02X1069000Y476998I-1418J3202D01*
G02X1067581Y477298I-1J3502D01*
G03X1067419I-81J-183D01*
G02X1066000Y476998I-1418J3202D01*
G02X1064581Y477298I-1J3502D01*
G03X1064419I-81J-183D01*
G02X1063000Y476998I-1418J3202D01*
G02X1061581Y477298I-1J3502D01*
G03X1061419I-81J-183D01*
G02X1060000Y476998I-1418J3202D01*
G02X1056498Y480500I0J3502D01*
G02X1056798Y481919I3502J1D01*
G03Y482081I-183J81D01*
G02X1056498Y483500I3202J1418D01*
G02X1056798Y484919I3502J1D01*
G03Y485081I-183J81D01*
G02X1056498Y486500I3202J1418D01*
G02X1056798Y487919I3502J1D01*
G03Y488081I-183J81D01*
G02X1056498Y489500I3202J1418D01*
G02X1056798Y490919I3502J1D01*
G03Y491081I-183J81D01*
G02X1056498Y492500I3202J1418D01*
G02X1056798Y493919I3502J1D01*
G03Y494081I-183J81D01*
G02X1056498Y495500I3202J1418D01*
G02X1060000Y499002I3502J0D01*
G02X1061419Y498702I1J-3502D01*
G03X1061581I81J183D01*
G02X1063000Y499002I1418J-3202D01*
G02X1064419Y498702I1J-3502D01*
G03X1064581I81J183D01*
G37*
G36*
G01X170520Y501202D02*
G02X171939Y501502I1418J-3202D01*
G02Y494498I0J-3502D01*
G02X170520Y494798I-1J3502D01*
G03X170358I-81J-183D01*
G02X168939Y494498I-1418J3202D01*
G02Y501502I0J3502D01*
G02X170358Y501202I1J-3502D01*
G03X170520I81J183D01*
G37*
G36*
G01X218520D02*
G02X219939Y501502I1418J-3202D01*
G02Y494498I0J-3502D01*
G02X218520Y494798I-1J3502D01*
G03X218358I-81J-183D01*
G02X216939Y494498I-1418J3202D01*
G02Y501502I0J3502D01*
G02X218358Y501202I1J-3502D01*
G03X218520I81J183D01*
G37*
G36*
G01X266520D02*
G02X267939Y501502I1418J-3202D01*
G02Y494498I0J-3502D01*
G02X266520Y494798I-1J3502D01*
G03X266358I-81J-183D01*
G02X264939Y494498I-1418J3202D01*
G02Y501502I0J3502D01*
G02X266358Y501202I1J-3502D01*
G03X266520I81J183D01*
G37*
G36*
G01X328000D02*
G02X329419Y501502I1418J-3202D01*
G02Y494498I0J-3502D01*
G02X328000Y494798I-1J3502D01*
G03X327838I-81J-183D01*
G02X326419Y494498I-1418J3202D01*
G02Y501502I0J3502D01*
G02X327838Y501202I1J-3502D01*
G03X328000I81J183D01*
G37*
G36*
G01X376000D02*
G02X377419Y501502I1418J-3202D01*
G02Y494498I0J-3502D01*
G02X376000Y494798I-1J3502D01*
G03X375838I-81J-183D01*
G02X374419Y494498I-1418J3202D01*
G02Y501502I0J3502D01*
G02X375838Y501202I1J-3502D01*
G03X376000I81J183D01*
G37*
G36*
G01X424000D02*
G02X425419Y501502I1418J-3202D01*
G02Y494498I0J-3502D01*
G02X424000Y494798I-1J3502D01*
G03X423838I-81J-183D01*
G02X422419Y494498I-1418J3202D01*
G02Y501502I0J3502D01*
G02X423838Y501202I1J-3502D01*
G03X424000I81J183D01*
G37*
G36*
G01X485481D02*
G02X486900Y501502I1418J-3202D01*
G02Y494498I0J-3502D01*
G02X485481Y494798I-1J3502D01*
G03X485319I-81J-183D01*
G02X483900Y494498I-1418J3202D01*
G02Y501502I0J3502D01*
G02X485319Y501202I1J-3502D01*
G03X485481I81J183D01*
G37*
G36*
G01X533481D02*
G02X534900Y501502I1418J-3202D01*
G02Y494498I0J-3502D01*
G02X533481Y494798I-1J3502D01*
G03X533319I-81J-183D01*
G02X531900Y494498I-1418J3202D01*
G02Y501502I0J3502D01*
G02X533319Y501202I1J-3502D01*
G03X533481I81J183D01*
G37*
G36*
G01X581481D02*
G02X582900Y501502I1418J-3202D01*
G02Y494498I0J-3502D01*
G02X581481Y494798I-1J3502D01*
G03X581319I-81J-183D01*
G02X579900Y494498I-1418J3202D01*
G02Y501502I0J3502D01*
G02X581319Y501202I1J-3502D01*
G03X581481I81J183D01*
G37*
G36*
G01X642962D02*
G02X644381Y501502I1418J-3202D01*
G02Y494498I0J-3502D01*
G02X642962Y494798I-1J3502D01*
G03X642800I-81J-183D01*
G02X641381Y494498I-1418J3202D01*
G02Y501502I0J3502D01*
G02X642800Y501202I1J-3502D01*
G03X642962I81J183D01*
G37*
G36*
G01X690962D02*
G02X692381Y501502I1418J-3202D01*
G02Y494498I0J-3502D01*
G02X690962Y494798I-1J3502D01*
G03X690800I-81J-183D01*
G02X689381Y494498I-1418J3202D01*
G02Y501502I0J3502D01*
G02X690800Y501202I1J-3502D01*
G03X690962I81J183D01*
G37*
G36*
G01X738962D02*
G02X740381Y501502I1418J-3202D01*
G02Y494498I0J-3502D01*
G02X738962Y494798I-1J3502D01*
G03X738800I-81J-183D01*
G02X737381Y494498I-1418J3202D01*
G02Y501502I0J3502D01*
G02X738800Y501202I1J-3502D01*
G03X738962I81J183D01*
G37*
G36*
G01X170520Y521202D02*
G02X171939Y521502I1418J-3202D01*
G02Y514498I0J-3502D01*
G02X170520Y514798I-1J3502D01*
G03X170358I-81J-183D01*
G02X168939Y514498I-1418J3202D01*
G02Y521502I0J3502D01*
G02X170358Y521202I1J-3502D01*
G03X170520I81J183D01*
G37*
G36*
G01X218520D02*
G02X219939Y521502I1418J-3202D01*
G02Y514498I0J-3502D01*
G02X218520Y514798I-1J3502D01*
G03X218358I-81J-183D01*
G02X216939Y514498I-1418J3202D01*
G02Y521502I0J3502D01*
G02X218358Y521202I1J-3502D01*
G03X218520I81J183D01*
G37*
G36*
G01X266520D02*
G02X267939Y521502I1418J-3202D01*
G02Y514498I0J-3502D01*
G02X266520Y514798I-1J3502D01*
G03X266358I-81J-183D01*
G02X264939Y514498I-1418J3202D01*
G02Y521502I0J3502D01*
G02X266358Y521202I1J-3502D01*
G03X266520I81J183D01*
G37*
G36*
G01X328000D02*
G02X329419Y521502I1418J-3202D01*
G02Y514498I0J-3502D01*
G02X328000Y514798I-1J3502D01*
G03X327838I-81J-183D01*
G02X326419Y514498I-1418J3202D01*
G02Y521502I0J3502D01*
G02X327838Y521202I1J-3502D01*
G03X328000I81J183D01*
G37*
G36*
G01X376000D02*
G02X377419Y521502I1418J-3202D01*
G02Y514498I0J-3502D01*
G02X376000Y514798I-1J3502D01*
G03X375838I-81J-183D01*
G02X374419Y514498I-1418J3202D01*
G02Y521502I0J3502D01*
G02X375838Y521202I1J-3502D01*
G03X376000I81J183D01*
G37*
G36*
G01X424000D02*
G02X425419Y521502I1418J-3202D01*
G02Y514498I0J-3502D01*
G02X424000Y514798I-1J3502D01*
G03X423838I-81J-183D01*
G02X422419Y514498I-1418J3202D01*
G02Y521502I0J3502D01*
G02X423838Y521202I1J-3502D01*
G03X424000I81J183D01*
G37*
G36*
G01X485481D02*
G02X486900Y521502I1418J-3202D01*
G02Y514498I0J-3502D01*
G02X485481Y514798I-1J3502D01*
G03X485319I-81J-183D01*
G02X483900Y514498I-1418J3202D01*
G02Y521502I0J3502D01*
G02X485319Y521202I1J-3502D01*
G03X485481I81J183D01*
G37*
G36*
G01X533481D02*
G02X534900Y521502I1418J-3202D01*
G02Y514498I0J-3502D01*
G02X533481Y514798I-1J3502D01*
G03X533319I-81J-183D01*
G02X531900Y514498I-1418J3202D01*
G02Y521502I0J3502D01*
G02X533319Y521202I1J-3502D01*
G03X533481I81J183D01*
G37*
G36*
G01X581481D02*
G02X582900Y521502I1418J-3202D01*
G02Y514498I0J-3502D01*
G02X581481Y514798I-1J3502D01*
G03X581319I-81J-183D01*
G02X579900Y514498I-1418J3202D01*
G02Y521502I0J3502D01*
G02X581319Y521202I1J-3502D01*
G03X581481I81J183D01*
G37*
G36*
G01X642962D02*
G02X644381Y521502I1418J-3202D01*
G02Y514498I0J-3502D01*
G02X642962Y514798I-1J3502D01*
G03X642800I-81J-183D01*
G02X641381Y514498I-1418J3202D01*
G02Y521502I0J3502D01*
G02X642800Y521202I1J-3502D01*
G03X642962I81J183D01*
G37*
G36*
G01X690962D02*
G02X692381Y521502I1418J-3202D01*
G02Y514498I0J-3502D01*
G02X690962Y514798I-1J3502D01*
G03X690800I-81J-183D01*
G02X689381Y514498I-1418J3202D01*
G02Y521502I0J3502D01*
G02X690800Y521202I1J-3502D01*
G03X690962I81J183D01*
G37*
G36*
G01X738962D02*
G02X740381Y521502I1418J-3202D01*
G02Y514498I0J-3502D01*
G02X738962Y514798I-1J3502D01*
G03X738800I-81J-183D01*
G02X737381Y514498I-1418J3202D01*
G02Y521502I0J3502D01*
G02X738800Y521202I1J-3502D01*
G03X738962I81J183D01*
G37*
G36*
G01X916288Y522263D02*
G02X917596Y522516I1307J-3249D01*
G02X919015Y522216I1J-3502D01*
G03X919177I81J183D01*
G02X920596Y522516I1418J-3202D01*
G02X922015Y522216I1J-3502D01*
G03X922177I81J183D01*
G02X923596Y522516I1418J-3202D01*
G02X927098Y519014I0J-3502D01*
G02X926806Y517614I-3502J0D01*
G03X926803Y517461I184J-80D01*
G02X927044Y516184I-3261J-1277D01*
G02X926744Y514765I-3502J-1D01*
G03Y514603I183J-81D01*
G02X927044Y513184I-3202J-1418D01*
G02X926744Y511765I-3502J-1D01*
G03Y511603I183J-81D01*
G02X927044Y510184I-3202J-1418D01*
G02X926744Y508765I-3502J-1D01*
G03Y508603I183J-81D01*
G02X927044Y507184I-3202J-1418D01*
G02X926744Y505765I-3502J-1D01*
G03Y505603I183J-81D01*
G02X927044Y504184I-3202J-1418D01*
G02X926744Y502765I-3502J-1D01*
G03Y502603I183J-81D01*
G02X927044Y501184I-3202J-1418D01*
G02X926823Y499959I-3502J-1D01*
G03X926826Y499812I188J-70D01*
G02X927098Y498461I-3231J-1353D01*
G02X923595Y494958I-3503J0D01*
G02X922176Y495259I2J3503D01*
G03X922014I-81J-183D01*
G02X920595Y494958I-1421J3202D01*
G02X919176Y495259I2J3503D01*
G03X919014I-81J-183D01*
G02X917595Y494958I-1421J3202D01*
G02X916287Y495212I2J3503D01*
G03X916137I-75J-186D01*
G02X914829Y494958I-1310J3249D01*
G02X913410Y495259I2J3503D01*
G03X913248I-81J-183D01*
G02X911829Y494958I-1421J3202D01*
G02X908326Y498461I0J3503D01*
G02X908548Y499686I3503J-2D01*
G03X908545Y499833I-188J70D01*
G02X908274Y501184I3232J1351D01*
G02X908574Y502603I3502J1D01*
G03Y502765I-183J81D01*
G02X908274Y504184I3202J1418D01*
G02X908574Y505603I3502J1D01*
G03Y505765I-183J81D01*
G02X908274Y507184I3202J1418D01*
G02X908574Y508603I3502J1D01*
G03Y508765I-183J81D01*
G02X908274Y510184I3202J1418D01*
G02X908574Y511603I3502J1D01*
G03Y511765I-183J81D01*
G02X908274Y513184I3202J1418D01*
G02X908574Y514603I3502J1D01*
G03Y514765I-183J81D01*
G02X908274Y516184I3202J1418D01*
G02X908566Y517584I3502J0D01*
G03X908569Y517737I-184J80D01*
G02X908328Y519014I3261J1277D01*
G02X911830Y522516I3502J0D01*
G02X913249Y522216I1J-3502D01*
G03X913411I81J183D01*
G02X914830Y522516I1418J-3202D01*
G02X916138Y522263I1J-3502D01*
G03X916288I75J186D01*
G37*
G36*
G01X839232Y519045D02*
G02X838932Y520464I3202J1418D01*
G02X839232Y521883I3502J1D01*
G03Y522045I-183J81D01*
G02X838932Y523464I3202J1418D01*
G02X842434Y526966I3502J0D01*
G02X843834Y526675I2J-3502D01*
G03X843987Y526672I80J183D01*
G02X845263Y526912I1274J-3262D01*
G02X846682Y526612I1J-3502D01*
G03X846844I81J183D01*
G02X848263Y526912I1418J-3202D01*
G02X849596Y526649I1J-3502D01*
G03X849749I77J185D01*
G02X851082Y526912I1332J-3239D01*
G02X852501Y526612I1J-3502D01*
G03X852663I81J183D01*
G02X854082Y526912I1418J-3202D01*
G02X857584Y523410I0J-3502D01*
G02X857284Y521991I-3502J-1D01*
G03Y521829I183J-81D01*
G02X857584Y520410I-3202J-1418D01*
G02X857284Y518991I-3502J-1D01*
G03Y518829I183J-81D01*
G02X857584Y517410I-3202J-1418D01*
G02X857284Y515991I-3502J-1D01*
G03Y515829I183J-81D01*
G02X857584Y514410I-3202J-1418D01*
G02X857284Y512991I-3502J-1D01*
G03Y512829I183J-81D01*
G02X857584Y511410I-3202J-1418D01*
G02X857284Y509991I-3502J-1D01*
G03Y509829I183J-81D01*
G02X857584Y508410I-3202J-1418D01*
G02X857284Y506991I-3502J-1D01*
G03Y506829I183J-81D01*
G02X857584Y505410I-3202J-1418D01*
G02X857284Y503991I-3502J-1D01*
G03Y503829I183J-81D01*
G02X857584Y502410I-3202J-1418D01*
G02X854082Y498908I-3502J0D01*
G02X852663Y499208I-1J3502D01*
G03X852501I-81J-183D01*
G02X851082Y498908I-1418J3202D01*
G02X849749Y499171I-1J3502D01*
G03X849596I-76J-185D01*
G02X848263Y498908I-1332J3239D01*
G02X846844Y499208I-1J3502D01*
G03X846682I-81J-183D01*
G02X845263Y498908I-1418J3202D01*
G02X843863Y499199I-2J3502D01*
G03X843710Y499202I-80J-183D01*
G02X842434Y498962I-1274J3262D01*
G02X838932Y502464I0J3502D01*
G02X839232Y503883I3502J1D01*
G03Y504045I-183J81D01*
G02X838932Y505464I3202J1418D01*
G02X839232Y506883I3502J1D01*
G03Y507045I-183J81D01*
G02X838932Y508464I3202J1418D01*
G02X839232Y509883I3502J1D01*
G03Y510045I-183J81D01*
G02X838932Y511464I3202J1418D01*
G02X839232Y512883I3502J1D01*
G03Y513045I-183J81D01*
G02X838932Y514464I3202J1418D01*
G02X839232Y515883I3502J1D01*
G03Y516045I-183J81D01*
G02X838932Y517464I3202J1418D01*
G02X839232Y518883I3502J1D01*
G03Y519045I-183J81D01*
G37*
G36*
G01X1063298Y548581D02*
G02X1062998Y550000I3202J1418D01*
G02X1063298Y551419I3502J1D01*
G03Y551581I-183J81D01*
G02X1062998Y553000I3202J1418D01*
G02X1066500Y556502I3502J0D01*
G02X1067919Y556202I1J-3502D01*
G03X1068081I81J183D01*
G02X1069500Y556502I1418J-3202D01*
G02X1073002Y553000I0J-3502D01*
G02X1072702Y551581I-3502J-1D01*
G03Y551419I183J-81D01*
G02X1073002Y550000I-3202J-1418D01*
G02X1072702Y548581I-3502J-1D01*
G03Y548419I183J-81D01*
G02X1073002Y547000I-3202J-1418D01*
G02X1072702Y545581I-3502J-1D01*
G03Y545419I183J-81D01*
G02X1073002Y544000I-3202J-1418D01*
G02X1072702Y542581I-3502J-1D01*
G03Y542419I183J-81D01*
G02X1073002Y541000I-3202J-1418D01*
G02X1072702Y539581I-3502J-1D01*
G03Y539419I183J-81D01*
G02X1073002Y538000I-3202J-1418D01*
G02X1069500Y534498I-3502J0D01*
G02X1068081Y534798I-1J3502D01*
G03X1067919I-81J-183D01*
G02X1066500Y534498I-1418J3202D01*
G02X1062998Y538000I0J3502D01*
G02X1063298Y539419I3502J1D01*
G03Y539581I-183J81D01*
G02X1062998Y541000I3202J1418D01*
G02X1063298Y542419I3502J1D01*
G03Y542581I-183J81D01*
G02X1062998Y544000I3202J1418D01*
G02X1063298Y545419I3502J1D01*
G03Y545581I-183J81D01*
G02X1062998Y547000I3202J1418D01*
G02X1063298Y548419I3502J1D01*
G03Y548581I-183J81D01*
G37*
G36*
G01X159774Y229052D02*
G02X159348Y230728I3076J1674D01*
G02X162850Y234230I3502J0D01*
G02X164032Y234025I1J-3502D01*
G03X164168I68J188D01*
G02X165350Y234230I1181J-3297D01*
G02X168852Y230728I0J-3502D01*
G02X168426Y229052I-3502J-2D01*
G03Y228861I175J-95D01*
G02X168852Y227185I-3076J-1674D01*
G02X168426Y225509I-3502J-2D01*
G03Y225318I175J-95D01*
G02X168852Y223642I-3076J-1674D01*
G02X168425Y221966I-3503J0D01*
G03Y221774I176J-96D01*
G02X168852Y220098I-3076J-1676D01*
G02X166105Y216678I-3502J0D01*
G03X166073Y216297I43J-195D01*
G02X166132Y216273I-1290J-3256D01*
G03X166288I78J184D01*
G02X167660Y216552I1370J-3223D01*
G02X171162Y213050I0J-3502D01*
G02X170819Y211536I-3503J-2D01*
G03Y211364I180J-86D01*
G02X171162Y209850I-3160J-1512D01*
G02X167660Y206348I-3502J0D01*
G02X166288Y206627I-2J3502D01*
G03X166132I-78J-184D01*
G02X164760Y206348I-1370J3223D01*
G02X161258Y209850I0J3502D01*
G02X161601Y211364I3503J2D01*
G03Y211536I-180J86D01*
G02X161258Y213050I3160J1512D01*
G02X162709Y215889I3503J0D01*
G01X162761Y215926D01*
X162802Y216043D01*
X162671Y216526D01*
X162576Y216606D01*
X162513Y216612D01*
G02X159348Y220098I337J3486D01*
G02X159775Y221774I3503J0D01*
G03Y221966I-176J96D01*
G02X159348Y223642I3076J1676D01*
G02X159774Y225318I3502J2D01*
G03Y225509I-175J96D01*
G02X159348Y227185I3076J1674D01*
G02X159774Y228861I3502J2D01*
G03Y229052I-175J95D01*
G37*
G54D56*
X247441Y305975D03*
X404921D03*
X562402D03*
X719883D03*
X849000Y399000D03*
X1016614Y197767D03*
X1024340Y146600D03*
X1084325Y130197D03*
X1092000Y82500D03*
X154840Y244730D03*
X1067866Y507629D03*
X1061600Y513742D03*
Y466242D03*
X1067730Y460352D03*
X1060984Y418742D03*
X1086500Y403500D03*
X1067679Y317942D03*
X1061600Y323742D03*
X1086500Y356000D03*
X1080418Y373600D03*
X1067531Y412942D03*
X1158200Y137700D03*
X1061600Y276242D03*
X1067707Y365442D03*
X1067701Y270442D03*
X1152781Y165719D03*
X1152500Y186500D03*
G54D59*
X1226024Y286929D03*
G54D60*
X48780Y329724D03*
G54D57*
X268000Y240000D03*
X312500D03*
X357000D03*
X428500D03*
X472500D03*
X516500D03*
X578500D03*
X622500D03*
X666500D03*
X735981D03*
X779981D03*
X823981D03*
G54D55*
X165539Y539000D03*
X213539D03*
X261539D03*
X323019D03*
X371019D03*
X419019D03*
X480500D03*
X528500D03*
X576500D03*
X637981D03*
X685981D03*
X733981D03*
G54D58*
X253819Y477204D03*
X411299D03*
X568780D03*
X726261D03*
G54D52*
X19922Y367716D03*
Y214173D03*
G54D53*
X964460Y16950D03*
X877510Y558620D03*
X175000Y100500D03*
X1271654Y636929D03*
X619685D03*
G54D54*
X108858Y99724D03*
Y482205D03*
G54D51*
X665059Y149408D03*
X980059D03*
X529252Y129685D03*
X249252D03*
X1226024Y174429D03*
%LPC*%
G75*
G36*
G01X1102061Y377400D02*
X1173385D01*
G02X1173527Y377341I0J-200D01*
G01X1178112Y372756D01*
G02X1178171Y372614I-141J-142D01*
G01Y338657D01*
G02X1178140Y338551I-200J1D01*
G03X1177909Y337750I1271J-800D01*
G03X1178140Y336949I1502J-1D01*
G02X1178171Y336843I-169J-107D01*
G01Y335157D01*
G02X1178140Y335051I-200J1D01*
G03X1177909Y334250I1271J-800D01*
G03X1178140Y333449I1502J-1D01*
G02X1178171Y333343I-169J-107D01*
G01Y331657D01*
G02X1178140Y331551I-200J1D01*
G03X1177909Y330750I1271J-800D01*
G03X1178140Y329949I1502J-1D01*
G02X1178171Y329843I-169J-107D01*
G01Y328157D01*
G02X1178140Y328051I-200J1D01*
G03X1177909Y327250I1271J-800D01*
G03X1178140Y326449I1502J-1D01*
G02X1178171Y326343I-169J-107D01*
G01Y310199D01*
X1178168Y310183D01*
G03X1178149Y309942I1483J-238D01*
G03X1178168Y309701I1502J-3D01*
G01X1178171Y309685D01*
Y306199D01*
X1178168Y306183D01*
G03X1178149Y305942I1483J-238D01*
G03X1178168Y305701I1502J-3D01*
G01X1178171Y305685D01*
Y240893D01*
G02X1178112Y240751I-200J0D01*
G01X1174527Y237166D01*
G02X1174385Y237107I-142J141D01*
G01X1101890D01*
G02X1101748Y237166I0J200D01*
G01X1097334Y241580D01*
G02X1097275Y241722I141J142D01*
G01Y372614D01*
G02X1097334Y372756I200J0D01*
G01X1101919Y377341D01*
G02X1102061Y377400I142J-141D01*
G37*
G36*
G01X1101564Y521466D02*
X1174418D01*
G02X1174560Y521407I0J-200D01*
G01X1178112Y517855D01*
G02X1178171Y517713I-141J-142D01*
G01Y480974D01*
X1178161Y480931D01*
X1178151Y480910D01*
G03X1177998Y480250I1349J-660D01*
G03X1178151Y479590I1502J0D01*
G01X1178161Y479569D01*
X1178171Y479526D01*
Y477474D01*
X1178161Y477431D01*
X1178151Y477410D01*
G03X1177998Y476750I1349J-660D01*
G03X1178151Y476090I1502J0D01*
G01X1178161Y476069D01*
X1178171Y476026D01*
Y473974D01*
X1178161Y473931D01*
X1178151Y473910D01*
G03X1177998Y473250I1349J-660D01*
G03X1178151Y472590I1502J0D01*
G01X1178161Y472569D01*
X1178171Y472526D01*
Y470474D01*
X1178161Y470431D01*
X1178151Y470410D01*
G03X1177998Y469750I1349J-660D01*
G03X1178151Y469090I1502J0D01*
G01X1178161Y469069D01*
X1178171Y469026D01*
Y386186D01*
G02X1178112Y386044I-200J0D01*
G01X1173527Y381459D01*
G02X1173385Y381400I-142J141D01*
G01X1102061D01*
G02X1101919Y381459I0J200D01*
G01X1097334Y386044D01*
G02X1097275Y386186I141J142D01*
G01Y517177D01*
G02X1097334Y517319I200J0D01*
G01X1101422Y521407D01*
G02X1101564Y521466I142J-141D01*
G37*
G36*
G01X1205314Y291525D02*
X1184505D01*
G02X1184363Y291584I0J200D01*
G01X1182230Y293717D01*
G02X1182171Y293859I141J142D01*
G01Y348245D01*
G02X1182208Y348361I200J0D01*
G03Y350107I-1222J873D01*
G02X1182171Y350223I163J116D01*
G01Y474987D01*
G02X1182230Y475129I200J0D01*
G01X1186142Y479041D01*
G02X1186284Y479100I142J-141D01*
G01X1257489D01*
G02X1257631Y479041I0J-200D01*
G01X1261441Y475231D01*
G02X1261500Y475089I-141J-142D01*
G01Y303511D01*
G02X1261441Y303369I-200J0D01*
G01X1258631Y300559D01*
G02X1258489Y300500I-142J141D01*
G01X1215200D01*
G03X1213786Y299914I0J-1999D01*
G01X1205456Y291584D01*
G02X1205314Y291525I-142J141D01*
G37*
%LPD*%
G75*
G54D61*
X1226024Y399429D03*
G54D20*
X63436Y353962D03*
X108600Y258560D03*
X111600D03*
X108600Y261560D03*
X111600D03*
X108600Y255560D03*
X111600D03*
X123000Y414500D03*
X119500D03*
Y411500D03*
X123000D03*
X119500Y408500D03*
X123000D03*
X119500Y417500D03*
X123000D03*
X119500Y420500D03*
X123000D03*
X115700Y420600D03*
Y417600D03*
Y408600D03*
Y411600D03*
Y414600D03*
X123000Y426600D03*
X119500D03*
X123000Y423600D03*
X119500D03*
X115700Y423700D03*
Y426700D03*
X150634Y219063D03*
X154840Y244730D03*
X155034Y228063D03*
Y224563D03*
X152334Y223063D03*
Y226563D03*
Y230063D03*
X155034Y231563D03*
X182260Y197050D03*
X179460D03*
X176560D03*
X174660Y205850D03*
Y202650D03*
X167660Y213050D03*
X164760D03*
X167660Y209850D03*
X164760D03*
X183900Y216830D03*
X178265Y213443D03*
X175976Y218775D03*
X165840Y247805D03*
X169840D03*
X166068Y238749D03*
X173869Y228168D03*
X175481Y225183D03*
X160017Y237764D03*
X161400Y323200D03*
X157000Y414500D03*
X160500D03*
Y417500D03*
X157000D03*
X160500Y420500D03*
X157000D03*
X160500Y411500D03*
X157000D03*
X160500Y408500D03*
X157000D03*
X164000Y414600D03*
Y417600D03*
Y420600D03*
Y411600D03*
Y408600D03*
X160300Y423600D03*
X156800D03*
X160300Y426600D03*
X156800D03*
X163800Y426700D03*
Y423700D03*
X168939Y498000D03*
X171939D03*
Y518000D03*
X168939D03*
X194160Y205200D03*
Y208200D03*
X200160Y205200D03*
Y208200D03*
X197160Y205200D03*
Y208200D03*
X185260Y205350D03*
Y208350D03*
X203575Y297500D03*
X212925Y315500D03*
X218500Y309500D03*
X226975D03*
X235975D03*
X230425Y313605D03*
X221425Y313000D03*
X216939Y498000D03*
X219939D03*
Y518000D03*
X216939D03*
X247441Y305975D03*
X264939Y498000D03*
X267939D03*
Y518000D03*
X264939D03*
X283000Y203500D03*
Y198500D03*
Y196000D03*
Y206000D03*
X285219Y279078D03*
X281219D03*
X277219D03*
X285219Y275078D03*
X281219D03*
X277219D03*
X285219Y271078D03*
X281219D03*
X277219D03*
Y283078D03*
X281219D03*
X285219D03*
X326000Y203500D03*
Y198500D03*
Y196000D03*
Y206000D03*
X304500Y203500D03*
Y198500D03*
Y196000D03*
Y206000D03*
X326419Y498000D03*
X329419D03*
Y518000D03*
X326419D03*
X347500Y203500D03*
Y198500D03*
Y196000D03*
Y206000D03*
X361000Y305975D03*
X390500Y203500D03*
Y198500D03*
Y196000D03*
Y206000D03*
X369000Y203500D03*
Y198500D03*
Y196000D03*
Y206000D03*
X375500Y309500D03*
X383975D03*
X382963Y316400D03*
Y313750D03*
X374419Y498000D03*
X377419D03*
Y518000D03*
X374419D03*
X412000Y203500D03*
Y198500D03*
Y196000D03*
Y206000D03*
X404921Y305975D03*
X392975Y309500D03*
X442499Y279186D03*
X438499D03*
X434499D03*
X442499Y275186D03*
X438499D03*
X434499D03*
X442499Y271186D03*
X438499D03*
X434499D03*
Y283186D03*
X438499D03*
X442499D03*
X422419Y498000D03*
X425419D03*
Y518000D03*
X422419D03*
X483900Y498000D03*
X486900D03*
Y518000D03*
X483900D03*
X518575Y295500D03*
X533475Y310500D03*
X539619Y316400D03*
Y313400D03*
X531900Y498000D03*
X534900D03*
Y518000D03*
X531900D03*
X562402Y305975D03*
X542475Y310500D03*
X551475D03*
X562000Y442000D03*
X564500D03*
X590500Y203000D03*
Y198000D03*
Y195500D03*
Y205500D03*
X582900Y518000D03*
Y498000D03*
X579900D03*
Y518000D03*
X612000Y203000D03*
Y198000D03*
Y195500D03*
Y205500D03*
X640900Y42300D03*
X647999Y33000D03*
X638200Y44000D03*
Y46500D03*
X641100Y48100D03*
X655000Y203000D03*
Y198000D03*
Y195500D03*
Y205500D03*
X633500Y203000D03*
Y198000D03*
Y195500D03*
Y205500D03*
X644381Y518000D03*
Y498000D03*
X641381D03*
Y518000D03*
X690075Y39500D03*
X676500Y195500D03*
Y198000D03*
Y203000D03*
Y205500D03*
X676075Y299600D03*
X680400Y310500D03*
X703740Y41000D03*
X707000Y32000D03*
X694425Y29500D03*
X703740Y54118D03*
X697990Y195500D03*
Y198000D03*
Y203000D03*
Y205500D03*
X716100Y255987D03*
X700040Y258960D03*
X694406Y295500D03*
X690956Y310500D03*
X699956D03*
X708956D03*
X697100Y313400D03*
X704400Y358600D03*
X702200Y356000D03*
X697900Y352500D03*
X707750Y358750D03*
X692381Y518000D03*
Y498000D03*
X689381D03*
Y518000D03*
X747160Y30000D03*
Y38500D03*
Y64000D03*
Y47000D03*
Y55500D03*
X719490Y195500D03*
Y198000D03*
Y203000D03*
Y205500D03*
X719883Y305975D03*
X724000Y294500D03*
X742500Y328500D03*
Y324500D03*
Y334500D03*
X735075Y326000D03*
Y336000D03*
X731925D03*
X732000Y326000D03*
X742000Y341500D03*
X742500Y347700D03*
Y353200D03*
X740381Y518000D03*
Y498000D03*
X737381D03*
Y518000D03*
X750300Y27200D03*
X752560Y30100D03*
X749760D03*
X752560Y38600D03*
X749760D03*
X752560Y64100D03*
X749760D03*
X752560Y47100D03*
X749760D03*
X752560Y55600D03*
X749760D03*
X754000Y353500D03*
Y356957D03*
X748075Y366500D03*
X803900Y279425D03*
X803500Y259525D03*
X784855Y265184D03*
X790000Y259612D03*
X794900Y265979D03*
X806000Y265075D03*
X806500Y285500D03*
X800575Y338000D03*
X779100Y326820D03*
X798400Y323900D03*
X786500Y316700D03*
X793800Y323880D03*
X781500Y362700D03*
X803000Y357000D03*
Y346500D03*
X802975Y362000D03*
X792000Y358000D03*
X805323Y408150D03*
Y405150D03*
X799323D03*
Y408150D03*
X802323Y405150D03*
Y408150D03*
X796600Y408097D03*
Y405097D03*
X802323Y416916D03*
X799323D03*
X805323D03*
X802323Y413916D03*
X799323D03*
X805323D03*
Y411150D03*
X799323D03*
X802323D03*
X796600Y411097D03*
Y413863D03*
Y416863D03*
X799655Y474684D03*
Y480503D03*
Y477684D03*
X802655Y474684D03*
Y480503D03*
Y477684D03*
X805655Y474684D03*
Y480503D03*
Y477684D03*
X802655Y483503D03*
X805709Y486332D03*
X805655Y483503D03*
X796655Y474684D03*
Y480503D03*
Y477684D03*
X796709Y486332D03*
X796655Y483503D03*
X799709Y486332D03*
X799655Y483503D03*
X802709Y486332D03*
X831000Y270500D03*
X808500Y276075D03*
X836000Y270500D03*
X826000Y270525D03*
X833500Y268575D03*
X821000Y270525D03*
X816000D03*
X827602Y283500D03*
X836500Y302500D03*
X814500Y293000D03*
X811500Y329000D03*
X815500D03*
X823500D03*
X819500Y318500D03*
X808425Y334000D03*
X831750Y318250D03*
X829500Y354925D03*
X827000Y360475D03*
X811575Y344000D03*
X827000Y352500D03*
X808425Y344000D03*
X811323Y405150D03*
Y408150D03*
X808323D03*
Y405150D03*
Y416916D03*
X811323D03*
X808323Y413916D03*
X811323D03*
Y411150D03*
X808323D03*
X817153Y408096D03*
Y405096D03*
X814323Y405150D03*
Y408150D03*
Y416916D03*
X817153Y416862D03*
X814323Y413916D03*
X817153Y413862D03*
Y411096D03*
X814323Y411150D03*
X817709Y486332D03*
X817655Y483503D03*
X808655Y474684D03*
Y480503D03*
Y477684D03*
X811655Y474684D03*
Y480503D03*
Y477684D03*
X814655D03*
Y480503D03*
Y474684D03*
X808709Y486332D03*
X808655Y483503D03*
X811709Y486332D03*
X811655Y483503D03*
X814655D03*
X814709Y486332D03*
X817655Y474684D03*
Y480503D03*
Y477684D03*
X863600Y208900D03*
X841000Y270500D03*
X846000Y270525D03*
X851000D03*
X856000D03*
X843500Y268575D03*
X853500D03*
X850750Y250750D03*
X853000Y303500D03*
X861600Y304600D03*
X845000Y303000D03*
X848500Y335800D03*
X839692Y329592D03*
X854825Y330925D03*
X850500Y356925D03*
X843843Y354342D03*
X864500Y358500D03*
X849000Y399000D03*
X850390Y385878D03*
X847390D03*
X859253D03*
X856253D03*
X865542Y385771D03*
X859342Y413916D03*
X856342D03*
X865342D03*
X862342D03*
Y411150D03*
X865342D03*
X856342D03*
X859342D03*
X853619Y411097D03*
Y413863D03*
Y416863D03*
X862342Y408150D03*
Y405150D03*
X865342Y408150D03*
Y405150D03*
X856342D03*
Y408150D03*
X859342Y405150D03*
Y408150D03*
X853619Y408097D03*
Y405097D03*
X859342Y416916D03*
X856342D03*
X865342D03*
X862342D03*
X856257Y474684D03*
Y480503D03*
Y477684D03*
X859257Y474684D03*
Y480503D03*
Y477684D03*
X862257Y474684D03*
Y480503D03*
Y477684D03*
X859257Y483503D03*
X862311Y486332D03*
X862257Y483503D03*
X853257Y474684D03*
Y480503D03*
Y477684D03*
X853311Y486332D03*
X853257Y483503D03*
X856311Y486332D03*
X856257Y483503D03*
X859311Y486332D03*
X865311D03*
X865257Y483503D03*
Y474684D03*
Y480503D03*
Y477684D03*
X854082Y505410D03*
X848263D03*
X851082D03*
X854082Y508410D03*
X848263D03*
X851082D03*
X854082Y511410D03*
X848263D03*
X851082D03*
X854082Y514410D03*
X848263D03*
X851082D03*
X845263Y508410D03*
X842434Y511464D03*
X845263Y511410D03*
X842434Y514464D03*
X845263Y514410D03*
X854082Y502410D03*
X848263D03*
X851082D03*
X842434Y502464D03*
X845263Y502410D03*
X842434Y505464D03*
X845263Y505410D03*
X842434Y508464D03*
Y523464D03*
X845263Y523410D03*
X854082Y517410D03*
X848263D03*
X851082D03*
Y520410D03*
X848263D03*
X854082D03*
X842434Y517464D03*
X845263Y517410D03*
Y520410D03*
X842434Y520464D03*
X854082Y523410D03*
X848263D03*
X851082D03*
X868000Y271500D03*
X867000Y291260D03*
X870000Y304525D03*
X875000D03*
X880000D03*
X888000Y283475D03*
X870000Y312788D03*
X880000Y312855D03*
X875000Y347273D03*
X874000Y358475D03*
X885500Y352925D03*
X869000Y360500D03*
X893091Y385771D03*
X874405D03*
X877405D03*
X868542D03*
X884228D03*
X887228D03*
X868342Y416916D03*
X871342D03*
X868342Y413916D03*
X871342D03*
Y411150D03*
X868342D03*
X874172Y408096D03*
Y405096D03*
Y416862D03*
Y413862D03*
Y411096D03*
X871342Y405150D03*
Y408150D03*
X868342Y405150D03*
Y408150D03*
X868311Y486332D03*
X868257Y483503D03*
Y477684D03*
Y480503D03*
Y474684D03*
X871311Y486332D03*
X874311D03*
X874257Y477684D03*
Y480503D03*
Y474684D03*
X871257Y483503D03*
Y474684D03*
Y480503D03*
Y477684D03*
X874257Y483503D03*
X909000Y283475D03*
X904500Y292000D03*
X915000Y322425D03*
X912000Y332425D03*
X905941Y320366D03*
X903500Y327975D03*
X916260Y355000D03*
X910992Y361075D03*
X920000Y355525D03*
X923740Y345500D03*
X896091Y385771D03*
X912525Y385877D03*
X906662D03*
X903662D03*
X922454Y385771D03*
X915525Y385877D03*
X911776Y507184D03*
Y510184D03*
Y501184D03*
Y504184D03*
X923595Y498461D03*
X920595D03*
X920542Y504184D03*
X923542D03*
X920542Y501184D03*
X923542D03*
Y510184D03*
X920542D03*
X923542Y507184D03*
X920542D03*
Y513184D03*
X923542D03*
X911829Y498461D03*
X914829D03*
X917595D03*
X917542Y504184D03*
Y501184D03*
Y510184D03*
Y507184D03*
Y513184D03*
X914776D03*
Y507184D03*
Y510184D03*
Y501184D03*
Y504184D03*
X911776Y513184D03*
X920542Y516184D03*
X923542D03*
X917542D03*
X914776D03*
X911776D03*
X917596Y519014D03*
X914830D03*
X911830D03*
X923596D03*
X920596D03*
X940575Y304000D03*
X926000Y283475D03*
X937516Y300075D03*
X947000Y302475D03*
X940000Y283800D03*
X930500Y315460D03*
X943172Y310885D03*
X943171Y315385D03*
X935516Y361075D03*
X927000Y357925D03*
X943885Y352385D03*
X933357Y344843D03*
X933196Y353360D03*
X925454Y385771D03*
X944247Y385877D03*
X941247D03*
X931317Y385771D03*
X934317D03*
X950110Y385877D03*
X953110D03*
X1022575Y100925D03*
Y115500D03*
X1034500Y145000D03*
X1037000Y146300D03*
X1037500Y142000D03*
X1036500Y153500D03*
X1043936Y145745D03*
X1019040Y157310D03*
X1019030Y160330D03*
X1022168Y155877D03*
Y161783D03*
X1017909Y151424D03*
X1017837Y154280D03*
X1024340Y146600D03*
X1016614Y187267D03*
Y190267D03*
X1036500Y172000D03*
Y163000D03*
X1039016Y189075D03*
Y183027D03*
X1039538Y179208D03*
X1039016Y185925D03*
X1022000Y171200D03*
X1019700Y166600D03*
X1016614Y197767D03*
X1057525Y130500D03*
X1049356Y143900D03*
X1047159Y141487D03*
X1054500Y148500D03*
X1048000Y153500D03*
X1057525Y134000D03*
Y138600D03*
X1073154Y140800D03*
X1057500Y155877D03*
X1070715Y146500D03*
X1063500Y159814D03*
X1048000Y172000D03*
Y163000D03*
X1060500Y164500D03*
X1062500Y191500D03*
X1067000D03*
X1070000D03*
X1058000D03*
X1053830Y191670D03*
X1060000Y249000D03*
X1063000D03*
X1066000D03*
Y246000D03*
X1063000D03*
X1060000D03*
X1066000Y243000D03*
X1063000D03*
X1060000D03*
X1069000Y246000D03*
Y243000D03*
X1072000Y246000D03*
Y243000D03*
X1060000Y252000D03*
X1063000D03*
X1066000D03*
Y258000D03*
X1063000D03*
X1060000D03*
X1066000Y255000D03*
X1063000D03*
X1060000D03*
X1069000Y258000D03*
Y255000D03*
X1072000Y258000D03*
Y255000D03*
X1067701Y270442D03*
X1061600Y276242D03*
X1060000Y296500D03*
X1063000D03*
X1066000D03*
Y293500D03*
X1063000D03*
X1060000D03*
X1069000D03*
X1060000Y299500D03*
X1063000D03*
X1066000D03*
Y305500D03*
X1063000D03*
X1060000D03*
X1066000Y302500D03*
X1063000D03*
X1060000D03*
X1069000Y305500D03*
Y302500D03*
X1066000Y290500D03*
X1063000D03*
X1060000D03*
X1069000D03*
X1072000Y293500D03*
Y305500D03*
Y302500D03*
Y290500D03*
X1066000Y338000D03*
X1063000D03*
X1060000D03*
X1069000D03*
X1072000D03*
X1067679Y317942D03*
X1061600Y323742D03*
X1060000Y344000D03*
X1063000D03*
X1066000D03*
X1060000Y347000D03*
X1063000D03*
X1066000D03*
Y341000D03*
X1063000D03*
X1060000D03*
X1066000Y353000D03*
X1063000D03*
X1060000D03*
X1066000Y350000D03*
X1063000D03*
X1060000D03*
X1069000Y353000D03*
Y350000D03*
Y341000D03*
X1072000Y353000D03*
Y350000D03*
Y341000D03*
X1067707Y365442D03*
X1061600Y359642D03*
X1066000Y397500D03*
X1063000D03*
X1060000D03*
X1069000D03*
X1060000Y391500D03*
X1063000D03*
X1066000D03*
X1060000Y394500D03*
X1063000D03*
X1066000D03*
Y388500D03*
X1063000D03*
X1060000D03*
X1066000Y385500D03*
X1063000D03*
X1060000D03*
X1069000Y388500D03*
Y385500D03*
X1072000Y397500D03*
Y388500D03*
Y385500D03*
X1066000Y400500D03*
X1063000D03*
X1060000D03*
X1069000D03*
X1072000D03*
X1067531Y412942D03*
X1060984Y418742D03*
X1066000Y433000D03*
X1063000D03*
X1060000D03*
X1069000D03*
X1060000Y439000D03*
X1063000D03*
X1066000D03*
X1060000Y442000D03*
X1063000D03*
X1066000D03*
Y436000D03*
X1063000D03*
X1060000D03*
X1069000D03*
X1072000Y433000D03*
Y436000D03*
X1066000Y448000D03*
X1063000D03*
X1060000D03*
X1066000Y445000D03*
X1063000D03*
X1060000D03*
X1069000Y448000D03*
Y445000D03*
X1072000Y448000D03*
Y445000D03*
X1069000Y480500D03*
Y483500D03*
X1060000Y480500D03*
X1063000D03*
X1066000D03*
X1060000Y483500D03*
X1063000D03*
X1066000D03*
Y486500D03*
X1063000D03*
X1060000D03*
X1072000Y480500D03*
Y483500D03*
X1067730Y460352D03*
X1061600Y466242D03*
X1069000Y492500D03*
Y495500D03*
X1060000Y492500D03*
X1063000D03*
X1066000D03*
X1060000Y495500D03*
X1063000D03*
X1066000D03*
Y489500D03*
X1063000D03*
X1060000D03*
X1072000Y492500D03*
Y495500D03*
X1067866Y507629D03*
X1061600Y513742D03*
X1066500Y538000D03*
Y541000D03*
X1069500D03*
X1066500Y544000D03*
X1069500D03*
Y538000D03*
Y547000D03*
Y550000D03*
X1066500Y547000D03*
Y550000D03*
Y553000D03*
X1069500D03*
X1092000Y82500D03*
X1087000Y100000D03*
X1073200Y90900D03*
X1077200D03*
X1084325Y130197D03*
X1094493Y151856D03*
X1073154Y137800D03*
X1082000Y143600D03*
X1092000Y159500D03*
X1094500Y143144D03*
X1084401Y159260D03*
X1094024Y179500D03*
X1085000Y184575D03*
X1079500D03*
X1085525Y167500D03*
Y171000D03*
Y174500D03*
Y164000D03*
X1087500Y198000D03*
Y201000D03*
X1097500Y203700D03*
X1100000D03*
X1073500Y191500D03*
X1086500Y356000D03*
X1080418Y373600D03*
X1086500Y403500D03*
X1074316Y406925D03*
X1123000Y120816D03*
X1126000D03*
X1131500D03*
X1115800Y126600D03*
X1130125Y135940D03*
X1126075Y135973D03*
X1121238Y144500D03*
X1108500Y136500D03*
X1104500Y136524D03*
X1120524Y138457D03*
X1129000Y157000D03*
X1120200D03*
X1115425Y138925D03*
X1119000Y189500D03*
X1111100Y163749D03*
X1123500Y187000D03*
X1108000Y172000D03*
X1113368Y171619D03*
X1110800Y170000D03*
X1113129Y165719D03*
X1114500Y188700D03*
X1120200Y176500D03*
Y166500D03*
X1129000D03*
Y176500D03*
X1108821Y166800D03*
X1125918Y195418D03*
X1129068Y195500D03*
X1133000Y198000D03*
X1117206Y231741D03*
X1117290Y224241D03*
X1106189D03*
X1106106Y231741D03*
X1134500Y120816D03*
X1158200Y137700D03*
X1136300Y161100D03*
X1140000D03*
X1160200Y175982D03*
X1152781Y165719D03*
X1136300Y172300D03*
X1140000D03*
X1140336Y183560D03*
X1143490D03*
X1152500Y186500D03*
X1158000Y179000D03*
X1162700Y175959D03*
X1183021Y165952D03*
X1185521D03*
X1188600Y166000D03*
X1188618Y162782D03*
X1185521Y162952D03*
X1183021D03*
X1180521D03*
Y165952D03*
X1177521D03*
Y162952D03*
X1167600Y184500D03*
Y180500D03*
X1174500Y214000D03*
Y211000D03*
Y208000D03*
Y205000D03*
X1171500D03*
Y208000D03*
Y211000D03*
Y214000D03*
X1179651Y305942D03*
Y309942D03*
X1165070Y328750D03*
X1193411D03*
X1179411Y334250D03*
Y337750D03*
Y330750D03*
Y327250D03*
X1180986Y349234D03*
X1177836D03*
X1179877Y452442D03*
Y448442D03*
X1165190Y471250D03*
X1179500Y476750D03*
Y480250D03*
Y469750D03*
Y473250D03*
X1181075Y491734D03*
X1177925D03*
X1193840Y471250D03*
G54D12*
X72836Y47244D03*
Y535433D03*
X466536Y47244D03*
X860237D03*
X943225Y228000D03*
X985225Y542500D03*
G54D35*
X268000Y240000D03*
X312500D03*
X357000D03*
X428500D03*
X472500D03*
X516500D03*
X578500D03*
X622500D03*
X666500D03*
X735981D03*
X779981D03*
X823981D03*
G54D16*
X38780Y272598D03*
Y279291D03*
Y292598D03*
Y299291D03*
X48780Y272598D03*
Y279291D03*
Y292598D03*
Y299291D03*
G54D25*
X165350Y220098D03*
X162850D03*
Y227185D03*
Y230728D03*
X165350Y223642D03*
Y227185D03*
Y230728D03*
X162850Y223642D03*
G54D28*
X165539Y539000D03*
X213539D03*
X261539D03*
X323019D03*
X371019D03*
X419019D03*
X480500D03*
X528500D03*
X576500D03*
X637981D03*
X685981D03*
X733981D03*
G54D17*
X33780Y334724D03*
Y314724D03*
X38780Y319724D03*
Y329724D03*
Y339724D03*
X33780Y344724D03*
X38780Y349724D03*
X48780Y319724D03*
Y329724D03*
Y339724D03*
X43780Y314724D03*
Y324724D03*
Y334724D03*
X48780Y349724D03*
X43780Y344724D03*
G54D23*
X155140Y240230D03*
X172934Y219110D03*
X172712Y222263D03*
X183815Y220903D03*
X808500Y272925D03*
X831000Y260500D03*
X836000D03*
X825941Y339560D03*
X835610Y355590D03*
X841000Y260525D03*
X865000Y313200D03*
X878000Y358475D03*
X883000Y358500D03*
X1070400Y123200D03*
X1067600D03*
X1111452Y544000D03*
Y541000D03*
X1114452Y544000D03*
Y541000D03*
Y538000D03*
X1111452D03*
X1120669Y544000D03*
Y541000D03*
X1123669Y544000D03*
Y541000D03*
Y538000D03*
X1120669D03*
X1114452Y553000D03*
X1111452D03*
X1114452Y550000D03*
X1111452D03*
X1114452Y547000D03*
X1111452D03*
X1123669Y553000D03*
X1120669D03*
X1123669Y550000D03*
X1120669D03*
X1123669Y547000D03*
X1120669D03*
G54D27*
X180539Y498000D03*
X183539D03*
X228539D03*
X231539D03*
X276539D03*
X279539D03*
X338019D03*
X341019D03*
X386019D03*
X389019D03*
X434019D03*
X437019D03*
X498500D03*
X495500D03*
X546500D03*
X543500D03*
X594500D03*
X591500D03*
X655981D03*
X652981D03*
X703981D03*
X700981D03*
X748981D03*
X751981D03*
X826000Y260525D03*
X848075Y306500D03*
X912500Y327975D03*
X1159710Y306037D03*
X1156710D03*
X1159710Y303037D03*
X1156710D03*
X1159710Y300037D03*
X1156710D03*
X1159710Y297037D03*
X1156710D03*
Y294037D03*
X1159710D03*
Y309037D03*
X1156710D03*
X1159710Y312037D03*
X1156710D03*
X1159710Y321037D03*
X1156710D03*
X1159710Y318037D03*
X1156710D03*
X1159710Y315037D03*
X1156710D03*
X1159799Y448537D03*
X1156799D03*
X1159799Y445537D03*
X1156799D03*
X1159799Y442537D03*
X1156799D03*
X1159799Y439537D03*
X1156799D03*
Y436537D03*
X1159799D03*
Y454537D03*
X1156799D03*
X1159799Y451537D03*
X1156799D03*
X1159799Y457537D03*
X1156799D03*
X1159799Y463537D03*
X1156799D03*
X1159799Y460537D03*
X1156799D03*
X1162710Y306037D03*
Y303037D03*
Y300037D03*
Y297037D03*
Y294037D03*
Y309037D03*
Y312037D03*
Y321037D03*
Y318037D03*
Y315037D03*
X1162799Y448537D03*
Y445537D03*
Y442537D03*
Y439537D03*
Y436537D03*
Y454537D03*
Y451537D03*
Y457537D03*
Y463537D03*
Y460537D03*
G54D30*
X208071Y267204D03*
X200197D03*
X215945D03*
X231693D03*
X223819D03*
X239567D03*
X247441D03*
X357677D03*
X365551D03*
X373425D03*
X389173D03*
X381299D03*
X404921D03*
X397047D03*
X523032D03*
X515158D03*
X530906D03*
X538780D03*
X546654D03*
X562402D03*
X554528D03*
X680513D03*
X672639D03*
X688387D03*
X704135D03*
X696261D03*
X712009D03*
X719883D03*
G54D33*
X223819Y477204D03*
X253819D03*
X381299D03*
X411299D03*
X538780D03*
X568780D03*
X696261D03*
X726261D03*
G54D38*
X411752Y129685D03*
X401752D03*
X411752Y139685D03*
Y149685D03*
Y159685D03*
X401752Y139685D03*
Y149685D03*
Y159685D03*
X446752Y129685D03*
X436752D03*
X446752Y139685D03*
Y149685D03*
Y159685D03*
X436752Y139685D03*
Y149685D03*
Y159685D03*
X481752Y129685D03*
X471752D03*
X481752Y139685D03*
Y149685D03*
Y159685D03*
X471752Y139685D03*
Y149685D03*
Y159685D03*
X712559Y129408D03*
Y119408D03*
Y149408D03*
Y139408D03*
X722559Y129408D03*
Y119408D03*
X747559Y129408D03*
Y119408D03*
X722559Y149408D03*
Y139408D03*
X747559Y149408D03*
Y139408D03*
X757559Y129408D03*
Y119408D03*
Y149408D03*
Y139408D03*
X782559Y129408D03*
Y119408D03*
X792559Y129408D03*
Y119408D03*
X782559Y149408D03*
Y139408D03*
X792559Y149408D03*
Y139408D03*
X812559Y119408D03*
Y129408D03*
X822559Y119408D03*
Y129408D03*
X832559Y119408D03*
Y129408D03*
X812559Y149408D03*
X822559Y139408D03*
Y149408D03*
X832559Y139408D03*
Y149408D03*
X1226024Y286929D03*
X1236024D03*
X1246024D03*
X1256024D03*
G54D43*
X1011000Y98000D03*
Y118000D03*
X1161000Y90400D03*
X1151000D03*
X1171000D03*
G54D40*
X766498Y602542D03*
X766604Y630687D03*
X766498Y612542D03*
X766604Y640687D03*
X1082833Y602542D03*
Y612542D03*
Y630687D03*
Y640687D03*
G54D37*
X296752Y129685D03*
Y139685D03*
Y149685D03*
Y159685D03*
X331752Y129685D03*
X306752D03*
X331752Y139685D03*
Y149685D03*
Y159685D03*
X306752Y139685D03*
Y149685D03*
Y159685D03*
X341752Y129685D03*
Y139685D03*
Y149685D03*
Y159685D03*
X376752Y129685D03*
X366752D03*
X376752Y139685D03*
Y149685D03*
Y159685D03*
X366752Y139685D03*
Y149685D03*
Y159685D03*
X1226024Y221929D03*
X1236024D03*
X1246024D03*
X1226024Y231929D03*
X1236024D03*
X1246024D03*
X1226024Y256929D03*
X1236024D03*
X1246024D03*
X1226024Y266929D03*
X1236024D03*
X1246024D03*
X1226024Y306929D03*
X1236024D03*
X1246024D03*
X1226024Y316929D03*
X1236024D03*
X1246024D03*
X1226024Y341929D03*
X1236024D03*
X1246024D03*
X1226024Y351929D03*
X1236024D03*
X1246024D03*
X1256024Y221929D03*
Y231929D03*
Y256929D03*
Y266929D03*
Y306929D03*
Y316929D03*
Y341929D03*
Y351929D03*
G54D26*
X178819Y277204D03*
X193819D03*
X336299D03*
X351299D03*
X493780D03*
X508780D03*
X651261D03*
X666261D03*
G54D44*
X1011000Y108000D03*
G54D29*
X185224Y539000D03*
X233224D03*
X281224D03*
X342704D03*
X390704D03*
X438704D03*
X500185D03*
X548185D03*
X596185D03*
X657666D03*
X705666D03*
X753666D03*
G54D46*
X1096017Y635687D03*
G54D45*
Y607542D03*
G54D36*
X253819Y277204D03*
X268819D03*
X411299D03*
X426299D03*
X568780D03*
X583780D03*
X726261D03*
X741261D03*
G54D13*
X118111Y47244D03*
Y535433D03*
X511811Y47244D03*
X905512D03*
X988500Y228000D03*
X1030500Y542500D03*
G54D11*
X19685Y-614173D03*
Y636929D03*
X619685D03*
X1271654Y-614173D03*
Y636929D03*
G54D14*
X19922Y214173D03*
Y367716D03*
G54D24*
X175000Y100500D03*
X877510Y558620D03*
X964460Y16950D03*
G54D21*
X82795Y99724D03*
Y482205D03*
G54D32*
X249252Y129685D03*
X529252D03*
X665059Y149408D03*
X980059D03*
X1226024Y174429D03*
Y399429D03*
G54D19*
X60630Y99724D03*
Y482205D03*
X108858Y99724D03*
Y482205D03*
G54D22*
X153480Y213350D03*
X941035Y344474D03*
X1097100Y35582D03*
Y38582D03*
X1099600D03*
Y35582D03*
X1102100D03*
Y38582D03*
X1096961Y18126D03*
Y21126D03*
X1099461D03*
Y18126D03*
X1101961D03*
Y21126D03*
X1097101Y53737D03*
Y56737D03*
X1099601D03*
Y53737D03*
X1102101D03*
Y56737D03*
X1125170Y35582D03*
Y38582D03*
X1127670D03*
Y35582D03*
X1130170D03*
Y38582D03*
X1104600Y35582D03*
Y38582D03*
X1107100Y35582D03*
Y38582D03*
X1104461Y18126D03*
Y21126D03*
X1106961Y18126D03*
Y21126D03*
X1130031D03*
Y18126D03*
X1127531D03*
Y21126D03*
X1125031D03*
Y18126D03*
X1104601Y53737D03*
Y56737D03*
X1107101Y53737D03*
Y56737D03*
X1132670Y35582D03*
X1135170D03*
Y38582D03*
X1132670D03*
X1135031Y21126D03*
Y18126D03*
X1132531Y21126D03*
Y18126D03*
X1132950Y82867D03*
Y85867D03*
X1135450D03*
Y82867D03*
X1137950D03*
X1140450D03*
X1142950D03*
Y85867D03*
X1140450D03*
X1137950D03*
X1183321Y123652D03*
X1185821D03*
X1188321D03*
Y120652D03*
X1185821D03*
X1183321D03*
X1180821D03*
Y123652D03*
X1178321D03*
Y120652D03*
G54D10*
X3005Y19808D03*
Y34808D03*
Y59808D03*
X7595Y128373D03*
X3005Y145238D03*
Y165238D03*
Y185238D03*
Y205238D03*
Y225238D03*
Y245238D03*
Y265238D03*
Y285238D03*
Y305238D03*
Y325238D03*
Y345238D03*
Y365238D03*
Y385238D03*
Y405238D03*
Y425238D03*
Y445238D03*
X3023Y524312D03*
Y549312D03*
X4540Y566003D03*
X34582Y3004D03*
X14811Y3732D03*
X12767Y72072D03*
X27271Y127298D03*
X19558Y454589D03*
X9913Y510026D03*
X20498Y575739D03*
X54582Y3004D03*
X39549Y454916D03*
X40498Y575739D03*
X60498D03*
X94582Y3004D03*
X74582D03*
X80498Y575739D03*
X114582Y3004D03*
X100498Y575739D03*
X120498D03*
X154582Y3004D03*
X134582D03*
X140400Y258360D03*
X143400D03*
X140400Y261360D03*
X143400D03*
X140400Y255360D03*
X143400D03*
X140498Y575739D03*
X174582Y3004D03*
X184349Y212651D03*
X173265Y340552D03*
X183539Y518000D03*
X180539D03*
X214582Y3004D03*
X194582D03*
X189760Y242100D03*
Y245100D03*
X192760Y242100D03*
Y245100D03*
X195760Y242100D03*
Y245100D03*
X198760Y242100D03*
Y245100D03*
X201760Y242100D03*
Y245100D03*
X208071Y305975D03*
X234582Y3004D03*
X246000Y238500D03*
X242500Y243000D03*
Y247500D03*
X218500Y305000D03*
X226975D03*
X235975D03*
X239567Y305975D03*
X223819Y445025D03*
X231539Y518000D03*
X228539D03*
X254582Y3004D03*
X246000Y235500D03*
X294582Y3004D03*
X274582D03*
X297000Y206000D03*
Y203500D03*
Y198500D03*
Y196000D03*
X290720Y340338D03*
X279539Y518000D03*
X276539D03*
X314582Y3004D03*
X318500Y206000D03*
Y203500D03*
Y198500D03*
Y196000D03*
X313571Y340552D03*
X354582Y3004D03*
X334582D03*
X340000Y206000D03*
Y203500D03*
Y198500D03*
Y196000D03*
X361500Y206000D03*
Y203500D03*
Y198500D03*
Y196000D03*
X341019Y518000D03*
X338019D03*
X374582Y3004D03*
X383000Y206000D03*
Y203500D03*
Y198500D03*
Y196000D03*
X375475Y305000D03*
X383975D03*
X365551Y305975D03*
X381299Y445025D03*
X389019Y518000D03*
X386019D03*
X414582Y3004D03*
X394582D03*
X404500Y206000D03*
Y203500D03*
Y198500D03*
Y196000D03*
X402000Y235000D03*
Y238000D03*
X398500Y247000D03*
Y242500D03*
X393000Y305000D03*
X397047Y305975D03*
X434582Y3004D03*
X426000Y206000D03*
Y203500D03*
Y198500D03*
Y196000D03*
X447255Y340339D03*
X430019Y444260D03*
X432019Y452025D03*
X437019Y518000D03*
X434019D03*
X474582Y3004D03*
X454582D03*
X473095Y340339D03*
X494582Y3004D03*
X498500Y518000D03*
X495500D03*
X534582Y3004D03*
X514582D03*
X533475Y305500D03*
X523032Y305975D03*
X538780Y445025D03*
X554582Y3004D03*
X555500Y239000D03*
Y236000D03*
X552000Y243500D03*
Y247000D03*
X542475Y305500D03*
X551475D03*
X554528Y305975D03*
X545063Y340339D03*
X549500Y445024D03*
X546500Y518000D03*
X543500D03*
X594582Y3004D03*
X574582D03*
X587500Y444260D03*
X589500Y446500D03*
X594500Y518000D03*
X591500D03*
X614582Y3004D03*
X604500Y205500D03*
Y203000D03*
Y198000D03*
Y195500D03*
X626000Y205500D03*
Y203000D03*
Y198000D03*
Y195500D03*
X654582Y3004D03*
X634582D03*
X647975Y37000D03*
X660200Y56800D03*
X655300D03*
X652300D03*
X647500Y205500D03*
Y203000D03*
Y198000D03*
Y195500D03*
X655981Y518000D03*
X652981D03*
X674582Y3004D03*
X684525Y32500D03*
Y36500D03*
X683600Y56800D03*
X679000D03*
X676000D03*
X686500D03*
X671100D03*
X668100D03*
X663200D03*
X669000Y205500D03*
Y203000D03*
Y198000D03*
Y195500D03*
X680513Y305975D03*
X714582Y3004D03*
X694582D03*
X699500Y34500D03*
X696900Y53300D03*
X694200D03*
X691400D03*
X689900Y56600D03*
X693000D03*
X696100Y56700D03*
X706000Y61975D03*
X690500Y205500D03*
Y203000D03*
Y198000D03*
Y195500D03*
X711990D03*
Y198000D03*
Y203000D03*
Y205500D03*
X709500Y247000D03*
X709481Y243500D03*
X712981Y236000D03*
Y239000D03*
X712009Y305975D03*
X708956Y305500D03*
X690956D03*
X700000D03*
X696261Y445024D03*
X703981Y518000D03*
X700981D03*
X734582Y3004D03*
X733490Y195500D03*
Y198000D03*
Y203000D03*
Y205500D03*
X732100Y332400D03*
X742500Y361500D03*
X774582Y3004D03*
X754582D03*
X761560Y38500D03*
X758760D03*
X756160D03*
X761560Y30000D03*
X758760D03*
X756160D03*
X758900Y27400D03*
X761560Y55500D03*
X758760D03*
X756160D03*
X761560Y47000D03*
X758760D03*
X756160D03*
X761560Y64000D03*
X758760D03*
X756160D03*
X751981Y518000D03*
X748981D03*
X794582Y3004D03*
X797854Y259539D03*
X786500Y336484D03*
X834582Y3004D03*
X814582D03*
X809500Y259430D03*
X819500Y329000D03*
X827500D03*
X813975Y362000D03*
Y357000D03*
X854582Y3004D03*
X849490Y196000D03*
Y198500D03*
Y203500D03*
Y206000D03*
X846000Y260525D03*
X851000D03*
X856000D03*
X837575Y321000D03*
X844760Y336077D03*
X850500Y360075D03*
Y366000D03*
X847500D03*
X856500D03*
X859500D03*
X865500D03*
X894582Y3004D03*
X874582D03*
X894500Y283475D03*
X884000D03*
X877500D03*
X893363Y298740D03*
X883000Y293925D03*
X877500Y366000D03*
X874500D03*
X884000D03*
X887000D03*
X893500D03*
X868500D03*
X914582Y3004D03*
X915500Y283475D03*
X914500Y292000D03*
X905000Y283475D03*
X905941Y306500D03*
X916260Y337077D03*
X908000Y327975D03*
X896500Y366000D03*
X906000D03*
X903000D03*
X912500D03*
X915500D03*
X922000D03*
X901063Y352340D03*
X934582Y3004D03*
X933000Y293476D03*
X940000D03*
X947000D03*
X933196Y309910D03*
X925000Y366000D03*
X944000D03*
X941000D03*
X934500D03*
X950500D03*
X953500D03*
X931500D03*
X927000Y361075D03*
X940498Y575739D03*
X974582Y3004D03*
X954582D03*
X960498Y575739D03*
X980498D03*
X994582Y3004D03*
X1000498Y575739D03*
X1034582Y3004D03*
X1014582D03*
X1034500Y142000D03*
X1020498Y575739D03*
X1040498D03*
X1054582Y3004D03*
X1068900Y110000D03*
X1065000Y156425D03*
X1070715Y178585D03*
X1060498Y575739D03*
X1094582Y3004D03*
X1074582D03*
X1091000Y99500D03*
X1095100D03*
X1073200Y126000D03*
Y128800D03*
Y123200D03*
X1084740Y108000D03*
X1100075Y139925D03*
X1084260Y152600D03*
X1101903Y285019D03*
X1101796Y331894D03*
X1090500Y376500D03*
X1090443Y417343D03*
X1080498Y575739D03*
X1100498D03*
X1114582Y3004D03*
X1113000Y101240D03*
X1119500Y86000D03*
Y83000D03*
X1113500Y147500D03*
X1118774Y284699D03*
X1112902D03*
X1110019Y284806D03*
X1104786Y284912D03*
X1121657Y284592D03*
X1118667Y331574D03*
X1112795D03*
X1109912Y331681D03*
X1104679Y331787D03*
X1121550Y331467D03*
X1104009Y427245D03*
X1120880Y426925D03*
X1115008D03*
X1112125Y427032D03*
X1106892Y427138D03*
X1123763Y426818D03*
X1103800Y474339D03*
X1106683Y474232D03*
X1111916Y474126D03*
X1114799Y474019D03*
X1120671D03*
X1123554Y473912D03*
X1120498Y575739D03*
X1154582Y3004D03*
X1134582D03*
X1155000Y124913D03*
X1159300Y129700D03*
X1141500Y124425D03*
Y120500D03*
X1154000Y151500D03*
X1141500Y134575D03*
X1138203Y266860D03*
Y260860D03*
Y263860D03*
X1135203Y260860D03*
Y263860D03*
Y266860D03*
X1138203Y257860D03*
Y254860D03*
X1135203Y257860D03*
Y254860D03*
X1135403Y302360D03*
Y305360D03*
X1138403Y302360D03*
Y305360D03*
X1135403Y308360D03*
X1138403D03*
X1135403Y314360D03*
Y311360D03*
X1138403D03*
Y314360D03*
Y361979D03*
X1135403D03*
X1138403Y358979D03*
X1135403D03*
X1138403Y355979D03*
X1135403D03*
X1138403Y352979D03*
X1135403D03*
X1138403Y349979D03*
X1135403D03*
X1135190Y396965D03*
X1138190D03*
X1135190Y399965D03*
X1138190D03*
X1135190Y402965D03*
Y405965D03*
Y408965D03*
X1138190Y402965D03*
Y405965D03*
Y408965D03*
X1135404Y457228D03*
Y454228D03*
Y451228D03*
Y445228D03*
Y448228D03*
X1138404Y454228D03*
Y451228D03*
Y445228D03*
Y448228D03*
Y457228D03*
X1135622Y485732D03*
Y470732D03*
Y467732D03*
Y479732D03*
Y476732D03*
Y473732D03*
Y482732D03*
X1138622D03*
Y473732D03*
Y476732D03*
Y479732D03*
Y470732D03*
Y485732D03*
Y467732D03*
X1140498Y575739D03*
X1160498D03*
X1174582Y3004D03*
X1177475Y111500D03*
X1179500Y105500D03*
X1180498Y575739D03*
X1214582Y3004D03*
X1194582D03*
X1203887Y306894D03*
X1200887D03*
X1197887D03*
X1203887Y303894D03*
X1200887D03*
X1197887D03*
X1203887Y300894D03*
X1200887D03*
X1197887D03*
X1203887Y297894D03*
X1200887D03*
X1197887D03*
X1203887Y294894D03*
X1200887D03*
X1197887D03*
Y321894D03*
X1200887D03*
X1203887D03*
Y318894D03*
X1200887D03*
X1197887D03*
X1203887Y315894D03*
X1200887D03*
X1197887D03*
X1203887Y312894D03*
X1200887D03*
X1197887D03*
X1203887Y309894D03*
X1200887D03*
X1197887D03*
X1197976Y437394D03*
X1200976D03*
X1203976D03*
X1197976Y440394D03*
X1200976D03*
X1203976D03*
X1197976Y443394D03*
X1200976D03*
X1203976D03*
X1197976Y446394D03*
X1200976D03*
X1203976D03*
X1197976Y449394D03*
X1200976D03*
X1203976D03*
X1197976Y452394D03*
X1200976D03*
X1203976D03*
X1197976Y455394D03*
X1200976D03*
X1203976D03*
X1197976Y464394D03*
X1200976D03*
X1203976D03*
X1197976Y458394D03*
X1200976D03*
X1203976D03*
X1197976Y461394D03*
X1200976D03*
X1203976D03*
X1200498Y575739D03*
X1220498D03*
X1234582Y3004D03*
X1240498Y575739D03*
X1277657Y4128D03*
X1254582Y3004D03*
X1260498Y575739D03*
X1279438Y573806D03*
X1286766Y12634D03*
X1288331Y30962D03*
Y70962D03*
Y50962D03*
Y90962D03*
Y130962D03*
Y110962D03*
Y150962D03*
Y190962D03*
Y170962D03*
Y210962D03*
Y230962D03*
Y270962D03*
Y250962D03*
Y290962D03*
Y330962D03*
Y310962D03*
Y350962D03*
Y390962D03*
Y370962D03*
Y410962D03*
Y450962D03*
Y430962D03*
Y470962D03*
Y510962D03*
Y490962D03*
Y530962D03*
X1287616Y563889D03*
X1288331Y550962D03*
G54D42*
X812559Y139408D03*
X852559Y129408D03*
Y119408D03*
X862559Y129408D03*
Y119408D03*
X852559Y149408D03*
Y139408D03*
X862559Y149408D03*
Y139408D03*
X887559Y129408D03*
Y119408D03*
Y149408D03*
Y139408D03*
X897559Y129408D03*
Y119408D03*
X922559Y129408D03*
Y119408D03*
X897559Y149408D03*
Y139408D03*
X922559Y149408D03*
Y139408D03*
X932559Y129408D03*
Y119408D03*
Y149408D03*
Y139408D03*
G54D48*
X1226024Y174429D03*
Y399429D03*
G54D18*
X33780Y324724D03*
G54D34*
X268000Y220315D03*
X312500D03*
X357000D03*
X428500D03*
X472500D03*
X516500D03*
X578500D03*
X622500D03*
X666500D03*
X735981D03*
X779981D03*
X823981D03*
G54D15*
X38780Y232598D03*
Y239291D03*
Y252598D03*
Y259291D03*
X48780Y232598D03*
Y239291D03*
Y252598D03*
Y259291D03*
G54D47*
X1240158Y57480D03*
Y521260D03*
G54D31*
X193819Y477204D03*
X351299D03*
X508780D03*
X666261D03*
G54D39*
X753314Y607542D03*
G54D41*
X753420Y635687D03*
%LPC*%
G75*
G54D50*
G01X-297025Y-1013390D02*
Y1828909D01*
X3691357D01*
Y-1013390D01*
X-297025D01*
G01X4093Y-769672D02*
Y-844672D01*
X504093D01*
Y-769672D01*
X4093D01*
G01X16093Y-834672D02*
Y-839672D01*
G01X14636Y-834672D02*
X17550D01*
G01X22460Y-839672D02*
X19926D01*
Y-834672D01*
X22460D01*
G01X21446Y-837089D02*
X19926D01*
G01X25026Y-834672D02*
Y-839672D01*
X27560D01*
G01X31393Y-839839D02*
X31266Y-839755D01*
Y-839589D01*
X31393Y-839505D01*
X31520Y-839589D01*
Y-839755D01*
X31393Y-839839D01*
G01Y-837589D02*
X31266Y-837505D01*
Y-837339D01*
X31393Y-837255D01*
X31520Y-837339D01*
Y-837505D01*
X31393Y-837589D01*
G01X36176Y-841339D02*
X35543Y-840505D01*
X35226Y-839672D01*
Y-836339D01*
X35543Y-835505D01*
X36176Y-834672D01*
G01X41593D02*
X41086Y-834839D01*
X40706Y-835255D01*
X40453Y-835755D01*
X40263Y-836422D01*
X40200Y-837172D01*
X40263Y-837922D01*
X40453Y-838589D01*
X40706Y-839089D01*
X41086Y-839505D01*
X41593Y-839672D01*
X42100Y-839505D01*
X42480Y-839089D01*
X42733Y-838589D01*
X42923Y-837922D01*
X42986Y-837172D01*
X42923Y-836422D01*
X42733Y-835755D01*
X42480Y-835255D01*
X42100Y-834839D01*
X41593Y-834672D01*
G01X45300Y-838672D02*
X45680Y-839255D01*
X46186Y-839589D01*
X46756Y-839672D01*
X47263Y-839589D01*
X47770Y-839172D01*
X48086Y-838672D01*
X48150Y-838172D01*
X48023Y-837589D01*
X47580Y-837172D01*
X47136Y-837005D01*
X46566D01*
G01X47136D02*
X47516Y-836755D01*
X47833Y-836339D01*
X47960Y-835839D01*
X47833Y-835339D01*
X47516Y-834922D01*
X46946Y-834672D01*
X46376Y-834755D01*
X45806Y-835089D01*
G01X52110Y-841339D02*
X52743Y-840505D01*
X53060Y-839672D01*
Y-836339D01*
X52743Y-835505D01*
X52110Y-834672D01*
G01X55500Y-838672D02*
X55880Y-839255D01*
X56386Y-839589D01*
X56956Y-839672D01*
X57463Y-839589D01*
X57970Y-839172D01*
X58286Y-838672D01*
X58350Y-838172D01*
X58223Y-837589D01*
X57780Y-837172D01*
X57336Y-837005D01*
X56766D01*
G01X57336D02*
X57716Y-836755D01*
X58033Y-836339D01*
X58160Y-835839D01*
X58033Y-835339D01*
X57716Y-834922D01*
X57146Y-834672D01*
X56576Y-834755D01*
X56006Y-835089D01*
G01X60790Y-835505D02*
X61170Y-835005D01*
X61613Y-834755D01*
X62120Y-834672D01*
X62753Y-834839D01*
X63196Y-835255D01*
X63323Y-835755D01*
X63260Y-836255D01*
X63006Y-836672D01*
X61740Y-837505D01*
X61170Y-838089D01*
X60790Y-838922D01*
X60663Y-839672D01*
X63323D01*
G01X66966D02*
X67093Y-838589D01*
X67283Y-837672D01*
X67536Y-836839D01*
X67853Y-835922D01*
X68360Y-834672D01*
X65826D01*
G01X71370Y-838005D02*
X73016D01*
G01X76090Y-835505D02*
X76470Y-835005D01*
X76913Y-834755D01*
X77420Y-834672D01*
X78053Y-834839D01*
X78496Y-835255D01*
X78623Y-835755D01*
X78560Y-836255D01*
X78306Y-836672D01*
X77040Y-837505D01*
X76470Y-838089D01*
X76090Y-838922D01*
X75963Y-839672D01*
X78623D01*
G01X81000Y-838672D02*
X81380Y-839255D01*
X81886Y-839589D01*
X82456Y-839672D01*
X82963Y-839589D01*
X83470Y-839172D01*
X83786Y-838672D01*
X83850Y-838172D01*
X83723Y-837589D01*
X83280Y-837172D01*
X82836Y-837005D01*
X82266D01*
G01X82836D02*
X83216Y-836755D01*
X83533Y-836339D01*
X83660Y-835839D01*
X83533Y-835339D01*
X83216Y-834922D01*
X82646Y-834672D01*
X82076Y-834755D01*
X81506Y-835089D01*
G01X88253Y-839672D02*
Y-834672D01*
X85910Y-838255D01*
X89076D01*
G01X91200Y-838922D02*
X91580Y-839339D01*
X92023Y-839589D01*
X92593Y-839672D01*
X93163Y-839505D01*
X93606Y-839172D01*
X93923Y-838589D01*
X93986Y-837922D01*
X93860Y-837255D01*
X93543Y-836839D01*
X93100Y-836505D01*
X92656Y-836422D01*
X92213Y-836505D01*
X91643Y-836839D01*
X91833Y-834672D01*
X93543D01*
G01X101590Y-839672D02*
Y-834672D01*
X103996D01*
G01X103110Y-837089D02*
X101590D01*
G01X106310Y-839672D02*
X107893Y-834672D01*
X109476Y-839672D01*
G01X108906Y-837922D02*
X106880D01*
G01X111663Y-839672D02*
X114323Y-834672D01*
G01X111663D02*
X114323Y-839672D01*
G01X118093Y-839839D02*
X117966Y-839755D01*
Y-839589D01*
X118093Y-839505D01*
X118220Y-839589D01*
Y-839755D01*
X118093Y-839839D01*
G01Y-837589D02*
X117966Y-837505D01*
Y-837339D01*
X118093Y-837255D01*
X118220Y-837339D01*
Y-837505D01*
X118093Y-837589D01*
G01X122876Y-841339D02*
X122243Y-840505D01*
X121926Y-839672D01*
Y-836339D01*
X122243Y-835505D01*
X122876Y-834672D01*
G01X128293D02*
X127786Y-834839D01*
X127406Y-835255D01*
X127153Y-835755D01*
X126963Y-836422D01*
X126900Y-837172D01*
X126963Y-837922D01*
X127153Y-838589D01*
X127406Y-839089D01*
X127786Y-839505D01*
X128293Y-839672D01*
X128800Y-839505D01*
X129180Y-839089D01*
X129433Y-838589D01*
X129623Y-837922D01*
X129686Y-837172D01*
X129623Y-836422D01*
X129433Y-835755D01*
X129180Y-835255D01*
X128800Y-834839D01*
X128293Y-834672D01*
G01X132000Y-838672D02*
X132380Y-839255D01*
X132886Y-839589D01*
X133456Y-839672D01*
X133963Y-839589D01*
X134470Y-839172D01*
X134786Y-838672D01*
X134850Y-838172D01*
X134723Y-837589D01*
X134280Y-837172D01*
X133836Y-837005D01*
X133266D01*
G01X133836D02*
X134216Y-836755D01*
X134533Y-836339D01*
X134660Y-835839D01*
X134533Y-835339D01*
X134216Y-834922D01*
X133646Y-834672D01*
X133076Y-834755D01*
X132506Y-835089D01*
G01X138810Y-841339D02*
X139443Y-840505D01*
X139760Y-839672D01*
Y-836339D01*
X139443Y-835505D01*
X138810Y-834672D01*
G01X142200Y-838672D02*
X142580Y-839255D01*
X143086Y-839589D01*
X143656Y-839672D01*
X144163Y-839589D01*
X144670Y-839172D01*
X144986Y-838672D01*
X145050Y-838172D01*
X144923Y-837589D01*
X144480Y-837172D01*
X144036Y-837005D01*
X143466D01*
G01X144036D02*
X144416Y-836755D01*
X144733Y-836339D01*
X144860Y-835839D01*
X144733Y-835339D01*
X144416Y-834922D01*
X143846Y-834672D01*
X143276Y-834755D01*
X142706Y-835089D01*
G01X147616Y-839089D02*
X148060Y-839505D01*
X148566Y-839672D01*
X149073Y-839505D01*
X149516Y-839005D01*
X149833Y-838255D01*
X149960Y-837505D01*
Y-836589D01*
X149833Y-835839D01*
X149516Y-835172D01*
X149136Y-834839D01*
X148693Y-834672D01*
X148186Y-834839D01*
X147806Y-835172D01*
X147553Y-835672D01*
X147426Y-836339D01*
X147553Y-836922D01*
X147870Y-837505D01*
X148250Y-837839D01*
X148693Y-837922D01*
X149200Y-837755D01*
X149580Y-837339D01*
X149960Y-836589D01*
G01X153666Y-839672D02*
X153793Y-838589D01*
X153983Y-837672D01*
X154236Y-836839D01*
X154553Y-835922D01*
X155060Y-834672D01*
X152526D01*
G01X158070Y-838005D02*
X159716D01*
G01X162600Y-838672D02*
X162980Y-839255D01*
X163486Y-839589D01*
X164056Y-839672D01*
X164563Y-839589D01*
X165070Y-839172D01*
X165386Y-838672D01*
X165450Y-838172D01*
X165323Y-837589D01*
X164880Y-837172D01*
X164436Y-837005D01*
X163866D01*
G01X164436D02*
X164816Y-836755D01*
X165133Y-836339D01*
X165260Y-835839D01*
X165133Y-835339D01*
X164816Y-834922D01*
X164246Y-834672D01*
X163676Y-834755D01*
X163106Y-835089D01*
G01X167890Y-837589D02*
X168333Y-837005D01*
X168713Y-836672D01*
X169220Y-836505D01*
X169663Y-836672D01*
X169980Y-837005D01*
X170233Y-837505D01*
X170296Y-838089D01*
X170233Y-838589D01*
X169980Y-839089D01*
X169600Y-839505D01*
X169156Y-839672D01*
X168650Y-839505D01*
X168206Y-839005D01*
X167953Y-838255D01*
X167890Y-837422D01*
X168016Y-836339D01*
X168206Y-835755D01*
X168523Y-835172D01*
X168966Y-834755D01*
X169410Y-834672D01*
X169853Y-834839D01*
X170170Y-835255D01*
G01X174193Y-839672D02*
Y-834672D01*
X173433Y-835672D01*
G01Y-839672D02*
X174953D01*
G01X180053D02*
Y-834672D01*
X177710Y-838255D01*
X180876D01*
G01X199093Y-769672D02*
Y-844672D01*
G01Y-819672D02*
X302093D01*
Y-794672D01*
G01X199093D02*
X302093D01*
G01X309600Y-829672D02*
Y-824672D01*
X310866D01*
X311373Y-824922D01*
X311753Y-825255D01*
X312070Y-825755D01*
X312323Y-826339D01*
X312386Y-827172D01*
X312323Y-828005D01*
X312070Y-828589D01*
X311753Y-829089D01*
X311373Y-829422D01*
X310866Y-829672D01*
X309600D01*
G01X314510D02*
X316093Y-824672D01*
X317676Y-829672D01*
G01X317106Y-827922D02*
X315080D01*
G01X321193Y-824672D02*
Y-829672D01*
G01X319736Y-824672D02*
X322650D01*
G01X327560Y-829672D02*
X325026D01*
Y-824672D01*
X327560D01*
G01X326546Y-827089D02*
X325026D01*
G01X331393Y-829839D02*
X331266Y-829755D01*
Y-829589D01*
X331393Y-829505D01*
X331520Y-829589D01*
Y-829755D01*
X331393Y-829839D01*
G01Y-827589D02*
X331266Y-827505D01*
Y-827339D01*
X331393Y-827255D01*
X331520Y-827339D01*
Y-827505D01*
X331393Y-827589D01*
G01X304093Y-769672D02*
Y-844672D01*
G01X302093Y-769672D02*
Y-844672D01*
G01X304093Y-819672D02*
X504093D01*
G01X309726Y-804672D02*
Y-799672D01*
X311246D01*
X311753Y-799922D01*
X312133Y-800505D01*
X312260Y-801172D01*
X312133Y-801839D01*
X311816Y-802339D01*
X311246Y-802589D01*
X309726D01*
G01X314953Y-804839D02*
X317233Y-799672D01*
G01X319736Y-804672D02*
Y-799672D01*
X322650Y-804672D01*
Y-799672D01*
G01X326293Y-804839D02*
X326166Y-804755D01*
Y-804589D01*
X326293Y-804505D01*
X326420Y-804589D01*
Y-804755D01*
X326293Y-804839D01*
G01Y-802589D02*
X326166Y-802505D01*
Y-802339D01*
X326293Y-802255D01*
X326420Y-802339D01*
Y-802505D01*
X326293Y-802589D01*
G01X304093Y-794672D02*
X504093D01*
G01X309726Y-779672D02*
Y-774672D01*
X311246D01*
X311753Y-774922D01*
X312133Y-775505D01*
X312260Y-776172D01*
X312133Y-776839D01*
X311816Y-777339D01*
X311246Y-777589D01*
X309726D01*
G01X314826Y-779672D02*
Y-774672D01*
X316410D01*
X316916Y-774922D01*
X317233Y-775255D01*
X317360Y-775922D01*
X317233Y-776589D01*
X316853Y-777005D01*
X316410Y-777255D01*
X314826D01*
G01X316410D02*
X317360Y-779672D01*
G01X321193D02*
X320686Y-779589D01*
X320243Y-779255D01*
X319863Y-778755D01*
X319610Y-778172D01*
X319483Y-777505D01*
Y-776839D01*
X319610Y-776172D01*
X319863Y-775589D01*
X320243Y-775089D01*
X320686Y-774755D01*
X321193Y-774672D01*
X321700Y-774755D01*
X322143Y-775089D01*
X322523Y-775589D01*
X322776Y-776172D01*
X322903Y-776839D01*
Y-777505D01*
X322776Y-778172D01*
X322523Y-778755D01*
X322143Y-779255D01*
X321700Y-779589D01*
X321193Y-779672D01*
G01X325026Y-778672D02*
X325343Y-779172D01*
X325723Y-779505D01*
X326166Y-779672D01*
X326673Y-779505D01*
X327053Y-779172D01*
X327433Y-778672D01*
X327560Y-778005D01*
Y-774672D01*
G01X332660Y-779672D02*
X330126D01*
Y-774672D01*
X332660D01*
G01X331646Y-777089D02*
X330126D01*
G01X337886Y-775089D02*
X337506Y-774839D01*
X337063Y-774672D01*
X336556D01*
X335986Y-774922D01*
X335543Y-775339D01*
X335226Y-775839D01*
X334973Y-776672D01*
X334910Y-777422D01*
X335036Y-778172D01*
X335226Y-778672D01*
X335606Y-779172D01*
X336050Y-779505D01*
X336493Y-779672D01*
X336936D01*
X337380Y-779505D01*
X337760Y-779255D01*
X338076Y-778922D01*
G01X341593Y-774672D02*
Y-779672D01*
G01X340136Y-774672D02*
X343050D01*
G01X346693Y-779839D02*
X346566Y-779755D01*
Y-779589D01*
X346693Y-779505D01*
X346820Y-779589D01*
Y-779755D01*
X346693Y-779839D01*
G01Y-777589D02*
X346566Y-777505D01*
Y-777339D01*
X346693Y-777255D01*
X346820Y-777339D01*
Y-777505D01*
X346693Y-777589D01*
G01X419093Y-819672D02*
Y-844672D01*
G01X421726Y-822172D02*
Y-827172D01*
X424260D01*
G01X427333Y-822172D02*
X428853D01*
G01X428093D02*
Y-827172D01*
G01X427333D02*
X428853D01*
G01X433700Y-824505D02*
X433953Y-824255D01*
X434143Y-823839D01*
X434270Y-823255D01*
X434143Y-822755D01*
X433890Y-822422D01*
X433446Y-822172D01*
X431736D01*
Y-827172D01*
X433826D01*
X434270Y-826839D01*
X434523Y-826339D01*
X434650Y-825755D01*
X434523Y-825172D01*
X434143Y-824672D01*
X433700Y-824505D01*
X431736D01*
G01X438293Y-827339D02*
X438166Y-827255D01*
Y-827089D01*
X438293Y-827005D01*
X438420Y-827089D01*
Y-827255D01*
X438293Y-827339D01*
G01Y-825089D02*
X438166Y-825005D01*
Y-824839D01*
X438293Y-824755D01*
X438420Y-824839D01*
Y-825005D01*
X438293Y-825089D01*
G01X470106Y-847839D02*
X470213Y-847714D01*
X470293Y-847505D01*
X470346Y-847214D01*
X470293Y-846964D01*
X470186Y-846797D01*
X470000Y-846672D01*
X469280D01*
Y-849172D01*
X470160D01*
X470346Y-849005D01*
X470453Y-848755D01*
X470506Y-848464D01*
X470453Y-848172D01*
X470293Y-847922D01*
X470106Y-847839D01*
X469280D01*
G01X472573Y-849172D02*
Y-847505D01*
G01Y-847797D02*
X472466Y-847630D01*
X472306Y-847547D01*
X472120Y-847505D01*
X471933Y-847589D01*
X471773Y-847755D01*
X471666Y-848005D01*
X471613Y-848339D01*
X471666Y-848672D01*
X471773Y-848922D01*
X471933Y-849089D01*
X472120Y-849172D01*
X472306Y-849130D01*
X472466Y-849005D01*
X472573Y-848839D01*
G01X473893Y-848880D02*
X474026Y-849047D01*
X474213Y-849172D01*
X474373D01*
X474533Y-849089D01*
X474640Y-848964D01*
X474693Y-848797D01*
X474666Y-848547D01*
X474560Y-848422D01*
X474080Y-848172D01*
X473973Y-847880D01*
X474026Y-847672D01*
X474133Y-847547D01*
X474293Y-847505D01*
X474453Y-847547D01*
X474613Y-847672D01*
G01X476093Y-848047D02*
X476946D01*
X476866Y-847755D01*
X476733Y-847589D01*
X476546Y-847505D01*
X476360Y-847547D01*
X476200Y-847672D01*
X476093Y-847964D01*
X476040Y-848214D01*
Y-848464D01*
X476093Y-848714D01*
X476226Y-848964D01*
X476386Y-849130D01*
X476573Y-849172D01*
X476760Y-849089D01*
X476946Y-848839D01*
G01X478213Y-849172D02*
Y-846672D01*
G01Y-847922D02*
X478346Y-847672D01*
X478506Y-847547D01*
X478666Y-847505D01*
X478906Y-847589D01*
X479066Y-847755D01*
X479173Y-848047D01*
Y-848380D01*
X479120Y-848714D01*
X479013Y-848964D01*
X478826Y-849130D01*
X478666Y-849172D01*
X478506Y-849130D01*
X478346Y-849005D01*
X478213Y-848797D01*
G01X480893Y-849172D02*
X480733Y-849130D01*
X480573Y-848964D01*
X480466Y-848672D01*
X480413Y-848339D01*
X480466Y-848005D01*
X480573Y-847714D01*
X480733Y-847547D01*
X480893Y-847505D01*
X481053Y-847547D01*
X481213Y-847714D01*
X481320Y-848005D01*
X481346Y-848339D01*
X481320Y-848672D01*
X481213Y-848964D01*
X481053Y-849130D01*
X480893Y-849172D01*
G01X483573D02*
Y-847505D01*
G01Y-847797D02*
X483466Y-847630D01*
X483306Y-847547D01*
X483120Y-847505D01*
X482933Y-847589D01*
X482773Y-847755D01*
X482666Y-848005D01*
X482613Y-848339D01*
X482666Y-848672D01*
X482773Y-848922D01*
X482933Y-849089D01*
X483120Y-849172D01*
X483306Y-849130D01*
X483466Y-849005D01*
X483573Y-848839D01*
G01X484920Y-849172D02*
Y-847505D01*
G01Y-847839D02*
X485053Y-847672D01*
X485186Y-847547D01*
X485373Y-847505D01*
X485506Y-847547D01*
X485666Y-847672D01*
G01X487973Y-846672D02*
Y-849172D01*
G01Y-848797D02*
X487866Y-849005D01*
X487706Y-849130D01*
X487520Y-849172D01*
X487306Y-849089D01*
X487146Y-848880D01*
X487040Y-848630D01*
X487013Y-848339D01*
X487040Y-848047D01*
X487146Y-847797D01*
X487306Y-847589D01*
X487520Y-847505D01*
X487706Y-847547D01*
X487840Y-847630D01*
X487973Y-847797D01*
G01X491360Y-849172D02*
Y-846672D01*
X492026D01*
X492240Y-846797D01*
X492373Y-846964D01*
X492426Y-847297D01*
X492373Y-847630D01*
X492213Y-847839D01*
X492026Y-847964D01*
X491360D01*
G01X492026D02*
X492426Y-849172D01*
G01X493693Y-848047D02*
X494546D01*
X494466Y-847755D01*
X494333Y-847589D01*
X494146Y-847505D01*
X493960Y-847547D01*
X493800Y-847672D01*
X493693Y-847964D01*
X493640Y-848214D01*
Y-848464D01*
X493693Y-848714D01*
X493826Y-848964D01*
X493986Y-849130D01*
X494173Y-849172D01*
X494360Y-849089D01*
X494546Y-848839D01*
G01X495813Y-847505D02*
X496293Y-849172D01*
X496773Y-847505D01*
G01X498493Y-849255D02*
X498440Y-849214D01*
Y-849130D01*
X498493Y-849089D01*
X498546Y-849130D01*
Y-849214D01*
X498493Y-849255D01*
G01X500693Y-849172D02*
X500880Y-849130D01*
X501093Y-849005D01*
X501226Y-848797D01*
X501280Y-848505D01*
X501226Y-848214D01*
X501066Y-847964D01*
X500826Y-847839D01*
X500560D01*
X500400Y-847755D01*
X500266Y-847547D01*
X500213Y-847255D01*
X500293Y-846964D01*
X500480Y-846755D01*
X500693Y-846672D01*
X500906Y-846755D01*
X501093Y-846964D01*
X501173Y-847255D01*
X501120Y-847547D01*
X500986Y-847755D01*
X500826Y-847839D01*
X500560D01*
X500320Y-847964D01*
X500160Y-848214D01*
X500106Y-848505D01*
X500160Y-848797D01*
X500293Y-849005D01*
X500506Y-849130D01*
X500693Y-849172D01*
G01X503106Y-847839D02*
X503213Y-847714D01*
X503293Y-847505D01*
X503346Y-847214D01*
X503293Y-846964D01*
X503186Y-846797D01*
X503000Y-846672D01*
X502280D01*
Y-849172D01*
X503160D01*
X503346Y-849005D01*
X503453Y-848755D01*
X503506Y-848464D01*
X503453Y-848172D01*
X503293Y-847922D01*
X503106Y-847839D01*
X502280D01*
G01X465993Y-822172D02*
Y-827172D01*
G01X464536Y-822172D02*
X467450D01*
G01X471093Y-827172D02*
X470713Y-827089D01*
X470333Y-826755D01*
X470080Y-826172D01*
X469953Y-825505D01*
X470080Y-824839D01*
X470333Y-824255D01*
X470713Y-823922D01*
X471093Y-823839D01*
X471473Y-823922D01*
X471853Y-824255D01*
X472106Y-824839D01*
X472170Y-825505D01*
X472106Y-826172D01*
X471853Y-826755D01*
X471473Y-827089D01*
X471093Y-827172D01*
G01X476193D02*
X475813Y-827089D01*
X475433Y-826755D01*
X475180Y-826172D01*
X475053Y-825505D01*
X475180Y-824839D01*
X475433Y-824255D01*
X475813Y-823922D01*
X476193Y-823839D01*
X476573Y-823922D01*
X476953Y-824255D01*
X477206Y-824839D01*
X477270Y-825505D01*
X477206Y-826172D01*
X476953Y-826755D01*
X476573Y-827089D01*
X476193Y-827172D01*
G01X481293D02*
Y-822172D01*
G01X486393Y-827339D02*
X486266Y-827255D01*
Y-827089D01*
X486393Y-827005D01*
X486520Y-827089D01*
Y-827255D01*
X486393Y-827339D01*
G01Y-825089D02*
X486266Y-825005D01*
Y-824839D01*
X486393Y-824755D01*
X486520Y-824839D01*
Y-825005D01*
X486393Y-825089D01*
G01X462093Y-819672D02*
Y-844672D01*
G01Y-794672D02*
Y-819672D01*
G01X464726Y-802172D02*
Y-797172D01*
X466310D01*
X466816Y-797422D01*
X467133Y-797755D01*
X467260Y-798422D01*
X467133Y-799089D01*
X466753Y-799505D01*
X466310Y-799755D01*
X464726D01*
G01X466310D02*
X467260Y-802172D01*
G01X472360D02*
X469826D01*
Y-797172D01*
X472360D01*
G01X471346Y-799589D02*
X469826D01*
G01X474610Y-797172D02*
X476193Y-802172D01*
X477776Y-797172D01*
G01X481293Y-802339D02*
X481166Y-802255D01*
Y-802089D01*
X481293Y-802005D01*
X481420Y-802089D01*
Y-802255D01*
X481293Y-802339D01*
G01Y-800089D02*
X481166Y-800005D01*
Y-799839D01*
X481293Y-799755D01*
X481420Y-799839D01*
Y-800005D01*
X481293Y-800089D01*
G01X-297025Y-1013390D02*
Y1828909D01*
X3691357D01*
Y-1013390D01*
X-297025D01*
G01X16913Y-817022D02*
X18480D01*
Y-818912D01*
X18010Y-819542D01*
X17461Y-819962D01*
X16678Y-820172D01*
X15895Y-819962D01*
X15346Y-819542D01*
X14876Y-818912D01*
X14563Y-818177D01*
X14406Y-817337D01*
Y-816602D01*
X14563Y-815972D01*
X14876Y-815237D01*
X15346Y-814607D01*
X15816Y-814187D01*
X16443Y-813872D01*
X16991D01*
X17618Y-814082D01*
X18088Y-814502D01*
G01X21020Y-813872D02*
Y-818387D01*
X21333Y-819332D01*
X21960Y-819962D01*
X22743Y-820172D01*
X23526Y-819962D01*
X24153Y-819332D01*
X24466Y-818387D01*
Y-813872D01*
G01X28103D02*
X29983D01*
G01X29043D02*
Y-820172D01*
G01X28103D02*
X29983D01*
G01X33698Y-819332D02*
X34325Y-819857D01*
X35030Y-820172D01*
X35656D01*
X36283Y-819857D01*
X36753Y-819332D01*
X36988Y-818597D01*
X36831Y-817862D01*
X36440Y-817232D01*
X35735Y-816812D01*
X34795Y-816602D01*
X34246Y-816182D01*
X34011Y-815447D01*
X34168Y-814712D01*
X34560Y-814187D01*
X35108Y-813872D01*
X35656D01*
X36205Y-814082D01*
X36675Y-814607D01*
G01X39998Y-820172D02*
Y-813872D01*
G01X43288D02*
Y-820172D01*
G01Y-817022D02*
X39998D01*
G01X45985Y-820172D02*
X47943Y-813872D01*
X49901Y-820172D01*
G01X49196Y-817967D02*
X46690D01*
G01X52441Y-820172D02*
Y-813872D01*
X56045Y-820172D01*
Y-813872D01*
G01X65120Y-820172D02*
Y-813872D01*
X66686D01*
X67313Y-814187D01*
X67783Y-814607D01*
X68175Y-815237D01*
X68488Y-815972D01*
X68566Y-817022D01*
X68488Y-818072D01*
X68175Y-818807D01*
X67783Y-819437D01*
X67313Y-819857D01*
X66686Y-820172D01*
X65120D01*
G01X72203Y-813872D02*
X74083D01*
G01X73143D02*
Y-820172D01*
G01X72203D02*
X74083D01*
G01X77798Y-819332D02*
X78425Y-819857D01*
X79130Y-820172D01*
X79756D01*
X80383Y-819857D01*
X80853Y-819332D01*
X81088Y-818597D01*
X80931Y-817862D01*
X80540Y-817232D01*
X79835Y-816812D01*
X78895Y-816602D01*
X78346Y-816182D01*
X78111Y-815447D01*
X78268Y-814712D01*
X78660Y-814187D01*
X79208Y-813872D01*
X79756D01*
X80305Y-814082D01*
X80775Y-814607D01*
G01X85743Y-813872D02*
Y-820172D01*
G01X83941Y-813872D02*
X87545D01*
G01X92043Y-820382D02*
X91886Y-820277D01*
Y-820067D01*
X92043Y-819962D01*
X92200Y-820067D01*
Y-820277D01*
X92043Y-820382D01*
G01X98186Y-821327D02*
X98500Y-819962D01*
G01X104643Y-813872D02*
Y-820172D01*
G01X102841Y-813872D02*
X106445D01*
G01X108985Y-820172D02*
X110943Y-813872D01*
X112901Y-820172D01*
G01X112196Y-817967D02*
X109690D01*
G01X117243Y-820172D02*
X116616Y-820067D01*
X116068Y-819647D01*
X115598Y-819017D01*
X115285Y-818282D01*
X115128Y-817442D01*
Y-816602D01*
X115285Y-815762D01*
X115598Y-815027D01*
X116068Y-814397D01*
X116616Y-813977D01*
X117243Y-813872D01*
X117870Y-813977D01*
X118418Y-814397D01*
X118888Y-815027D01*
X119201Y-815762D01*
X119358Y-816602D01*
Y-817442D01*
X119201Y-818282D01*
X118888Y-819017D01*
X118418Y-819647D01*
X117870Y-820067D01*
X117243Y-820172D01*
G01X123543D02*
Y-817337D01*
X121976Y-813872D01*
G01X125110D02*
X123543Y-817337D01*
G01X128120Y-813872D02*
Y-818387D01*
X128433Y-819332D01*
X129060Y-819962D01*
X129843Y-820172D01*
X130626Y-819962D01*
X131253Y-819332D01*
X131566Y-818387D01*
Y-813872D01*
G01X134185Y-820172D02*
X136143Y-813872D01*
X138101Y-820172D01*
G01X137396Y-817967D02*
X134890D01*
G01X140641Y-820172D02*
Y-813872D01*
X144245Y-820172D01*
Y-813872D01*
G01X18166Y-824397D02*
X17696Y-824082D01*
X17148Y-823872D01*
X16521D01*
X15816Y-824187D01*
X15268Y-824712D01*
X14876Y-825342D01*
X14563Y-826392D01*
X14485Y-827337D01*
X14641Y-828282D01*
X14876Y-828912D01*
X15346Y-829542D01*
X15895Y-829962D01*
X16443Y-830172D01*
X16991D01*
X17540Y-829962D01*
X18010Y-829647D01*
X18401Y-829227D01*
G01X21803Y-823872D02*
X23683D01*
G01X22743D02*
Y-830172D01*
G01X21803D02*
X23683D01*
G01X29043Y-823872D02*
Y-830172D01*
G01X27241Y-823872D02*
X30845D01*
G01X35343Y-830172D02*
Y-827337D01*
X33776Y-823872D01*
G01X36910D02*
X35343Y-827337D01*
G01X46220Y-828912D02*
X46690Y-829647D01*
X47316Y-830067D01*
X48021Y-830172D01*
X48648Y-830067D01*
X49275Y-829542D01*
X49666Y-828912D01*
X49745Y-828282D01*
X49588Y-827547D01*
X49040Y-827022D01*
X48491Y-826812D01*
X47786D01*
G01X48491D02*
X48961Y-826497D01*
X49353Y-825972D01*
X49510Y-825342D01*
X49353Y-824712D01*
X48961Y-824187D01*
X48256Y-823872D01*
X47551Y-823977D01*
X46846Y-824397D01*
G01X52520Y-828912D02*
X52990Y-829647D01*
X53616Y-830067D01*
X54321Y-830172D01*
X54948Y-830067D01*
X55575Y-829542D01*
X55966Y-828912D01*
X56045Y-828282D01*
X55888Y-827547D01*
X55340Y-827022D01*
X54791Y-826812D01*
X54086D01*
G01X54791D02*
X55261Y-826497D01*
X55653Y-825972D01*
X55810Y-825342D01*
X55653Y-824712D01*
X55261Y-824187D01*
X54556Y-823872D01*
X53851Y-823977D01*
X53146Y-824397D01*
G01X58820Y-828912D02*
X59290Y-829647D01*
X59916Y-830067D01*
X60621Y-830172D01*
X61248Y-830067D01*
X61875Y-829542D01*
X62266Y-828912D01*
X62345Y-828282D01*
X62188Y-827547D01*
X61640Y-827022D01*
X61091Y-826812D01*
X60386D01*
G01X61091D02*
X61561Y-826497D01*
X61953Y-825972D01*
X62110Y-825342D01*
X61953Y-824712D01*
X61561Y-824187D01*
X60856Y-823872D01*
X60151Y-823977D01*
X59446Y-824397D01*
G01X66686Y-830172D02*
X66843Y-828807D01*
X67078Y-827652D01*
X67391Y-826602D01*
X67783Y-825447D01*
X68410Y-823872D01*
X65276D01*
G01X72986Y-830172D02*
X73143Y-828807D01*
X73378Y-827652D01*
X73691Y-826602D01*
X74083Y-825447D01*
X74710Y-823872D01*
X71576D01*
G01X79286Y-831327D02*
X79600Y-829962D01*
G01X85743Y-823872D02*
Y-830172D01*
G01X83941Y-823872D02*
X87545D01*
G01X90085Y-830172D02*
X92043Y-823872D01*
X94001Y-830172D01*
G01X93296Y-827967D02*
X90790D01*
G01X97403Y-823872D02*
X99283D01*
G01X98343D02*
Y-830172D01*
G01X97403D02*
X99283D01*
G01X102293Y-823872D02*
X103390Y-830172D01*
X104643Y-823872D01*
X105896Y-830172D01*
X106993Y-823872D01*
G01X108985Y-830172D02*
X110943Y-823872D01*
X112901Y-830172D01*
G01X112196Y-827967D02*
X109690D01*
G01X115441Y-830172D02*
Y-823872D01*
X119045Y-830172D01*
Y-823872D01*
G01X129451Y-832272D02*
X128668Y-831222D01*
X128276Y-830172D01*
Y-825972D01*
X128668Y-824922D01*
X129451Y-823872D01*
G01X140876Y-830172D02*
Y-823872D01*
X142835D01*
X143461Y-824187D01*
X143853Y-824607D01*
X144010Y-825447D01*
X143853Y-826287D01*
X143383Y-826812D01*
X142835Y-827127D01*
X140876D01*
G01X142835D02*
X144010Y-830172D01*
G01X148743Y-830382D02*
X148586Y-830277D01*
Y-830067D01*
X148743Y-829962D01*
X148900Y-830067D01*
Y-830277D01*
X148743Y-830382D01*
G01X155043Y-830172D02*
X154416Y-830067D01*
X153868Y-829647D01*
X153398Y-829017D01*
X153085Y-828282D01*
X152928Y-827442D01*
Y-826602D01*
X153085Y-825762D01*
X153398Y-825027D01*
X153868Y-824397D01*
X154416Y-823977D01*
X155043Y-823872D01*
X155670Y-823977D01*
X156218Y-824397D01*
X156688Y-825027D01*
X157001Y-825762D01*
X157158Y-826602D01*
Y-827442D01*
X157001Y-828282D01*
X156688Y-829017D01*
X156218Y-829647D01*
X155670Y-830067D01*
X155043Y-830172D01*
G01X161343Y-830382D02*
X161186Y-830277D01*
Y-830067D01*
X161343Y-829962D01*
X161500Y-830067D01*
Y-830277D01*
X161343Y-830382D01*
G01X169366Y-824397D02*
X168896Y-824082D01*
X168348Y-823872D01*
X167721D01*
X167016Y-824187D01*
X166468Y-824712D01*
X166076Y-825342D01*
X165763Y-826392D01*
X165685Y-827337D01*
X165841Y-828282D01*
X166076Y-828912D01*
X166546Y-829542D01*
X167095Y-829962D01*
X167643Y-830172D01*
X168191D01*
X168740Y-829962D01*
X169210Y-829647D01*
X169601Y-829227D01*
G01X173943Y-830382D02*
X173786Y-830277D01*
Y-830067D01*
X173943Y-829962D01*
X174100Y-830067D01*
Y-830277D01*
X173943Y-830382D01*
G01X180635Y-832272D02*
X181418Y-831222D01*
X181810Y-830172D01*
Y-825972D01*
X181418Y-824922D01*
X180635Y-823872D01*
G01X38743Y-799472D02*
X36223Y-799055D01*
X34018Y-797389D01*
X32128Y-794889D01*
X30868Y-791972D01*
X30238Y-788639D01*
Y-785305D01*
X30868Y-781972D01*
X32128Y-779055D01*
X34018Y-776556D01*
X36223Y-774889D01*
X38743Y-774472D01*
X41263Y-774889D01*
X43468Y-776556D01*
X45358Y-779055D01*
X46618Y-781972D01*
X47248Y-785305D01*
Y-788639D01*
X46618Y-791972D01*
X45358Y-794889D01*
X43468Y-797389D01*
X41263Y-799055D01*
X38743Y-799472D01*
G01X41263Y-792805D02*
X45043Y-799472D01*
G01X58588Y-782806D02*
Y-794472D01*
X59848Y-797389D01*
X61738Y-799055D01*
X63943Y-799472D01*
X66148Y-799055D01*
X68038Y-797389D01*
X69298Y-794472D01*
G01Y-799472D02*
Y-782806D01*
G01X94813Y-799472D02*
Y-782806D01*
G01Y-785722D02*
X93553Y-784056D01*
X91663Y-783222D01*
X89458Y-782806D01*
X87253Y-783639D01*
X85363Y-785305D01*
X84103Y-787806D01*
X83473Y-791139D01*
X84103Y-794472D01*
X85363Y-796973D01*
X87253Y-798639D01*
X89458Y-799472D01*
X91663Y-799055D01*
X93553Y-797806D01*
X94813Y-796139D01*
G01X108988Y-799472D02*
Y-782806D01*
G01Y-786972D02*
X110248Y-784889D01*
X112138Y-783222D01*
X114658Y-782806D01*
X116863Y-783222D01*
X118753Y-784889D01*
X119698Y-787806D01*
Y-799472D01*
G01X139543Y-774472D02*
Y-799472D01*
G01X135133Y-782806D02*
X143953D01*
G01X170413Y-799472D02*
Y-782806D01*
G01Y-785722D02*
X169153Y-784056D01*
X167263Y-783222D01*
X165058Y-782806D01*
X162853Y-783639D01*
X160963Y-785305D01*
X159703Y-787806D01*
X159073Y-791139D01*
X159703Y-794472D01*
X160963Y-796973D01*
X162853Y-798639D01*
X165058Y-799472D01*
X167263Y-799055D01*
X169153Y-797806D01*
X170413Y-796139D01*
G01X14641Y-810172D02*
Y-803872D01*
X18245Y-810172D01*
Y-803872D01*
G01X22743Y-810172D02*
X22116Y-810067D01*
X21568Y-809647D01*
X21098Y-809017D01*
X20785Y-808282D01*
X20628Y-807442D01*
Y-806602D01*
X20785Y-805762D01*
X21098Y-805027D01*
X21568Y-804397D01*
X22116Y-803977D01*
X22743Y-803872D01*
X23370Y-803977D01*
X23918Y-804397D01*
X24388Y-805027D01*
X24701Y-805762D01*
X24858Y-806602D01*
Y-807442D01*
X24701Y-808282D01*
X24388Y-809017D01*
X23918Y-809647D01*
X23370Y-810067D01*
X22743Y-810172D01*
G01X29043Y-810382D02*
X28886Y-810277D01*
Y-810067D01*
X29043Y-809962D01*
X29200Y-810067D01*
Y-810277D01*
X29043Y-810382D01*
G01X33855Y-804922D02*
X34325Y-804292D01*
X34873Y-803977D01*
X35500Y-803872D01*
X36283Y-804082D01*
X36831Y-804607D01*
X36988Y-805237D01*
X36910Y-805867D01*
X36596Y-806392D01*
X35030Y-807442D01*
X34325Y-808177D01*
X33855Y-809227D01*
X33698Y-810172D01*
X36988D01*
G01X41643D02*
Y-803872D01*
X40703Y-805132D01*
G01Y-810172D02*
X42583D01*
G01X47943D02*
Y-803872D01*
X47003Y-805132D01*
G01Y-810172D02*
X48883D01*
G01X54086Y-811327D02*
X54400Y-809962D01*
G01X58193Y-803872D02*
X59290Y-810172D01*
X60543Y-803872D01*
X61796Y-810172D01*
X62893Y-803872D01*
G01X68410Y-810172D02*
X65276D01*
Y-803872D01*
X68410D01*
G01X67156Y-806917D02*
X65276D01*
G01X71341Y-810172D02*
Y-803872D01*
X74945Y-810172D01*
Y-803872D01*
G01X77798Y-810172D02*
Y-803872D01*
G01X81088D02*
Y-810172D01*
G01Y-807022D02*
X77798D01*
G01X84020Y-803872D02*
Y-808387D01*
X84333Y-809332D01*
X84960Y-809962D01*
X85743Y-810172D01*
X86526Y-809962D01*
X87153Y-809332D01*
X87466Y-808387D01*
Y-803872D01*
G01X90085Y-810172D02*
X92043Y-803872D01*
X94001Y-810172D01*
G01X93296Y-807967D02*
X90790D01*
G01X103155Y-804922D02*
X103625Y-804292D01*
X104173Y-803977D01*
X104800Y-803872D01*
X105583Y-804082D01*
X106131Y-804607D01*
X106288Y-805237D01*
X106210Y-805867D01*
X105896Y-806392D01*
X104330Y-807442D01*
X103625Y-808177D01*
X103155Y-809227D01*
X102998Y-810172D01*
X106288D01*
G01X109141D02*
Y-803872D01*
X112745Y-810172D01*
Y-803872D01*
G01X115520Y-810172D02*
Y-803872D01*
X117086D01*
X117713Y-804187D01*
X118183Y-804607D01*
X118575Y-805237D01*
X118888Y-805972D01*
X118966Y-807022D01*
X118888Y-808072D01*
X118575Y-808807D01*
X118183Y-809437D01*
X117713Y-809857D01*
X117086Y-810172D01*
X115520D01*
G01X128276D02*
Y-803872D01*
X130235D01*
X130861Y-804187D01*
X131253Y-804607D01*
X131410Y-805447D01*
X131253Y-806287D01*
X130783Y-806812D01*
X130235Y-807127D01*
X128276D01*
G01X130235D02*
X131410Y-810172D01*
G01X134420D02*
Y-803872D01*
X135986D01*
X136613Y-804187D01*
X137083Y-804607D01*
X137475Y-805237D01*
X137788Y-805972D01*
X137866Y-807022D01*
X137788Y-808072D01*
X137475Y-808807D01*
X137083Y-809437D01*
X136613Y-809857D01*
X135986Y-810172D01*
X134420D01*
G01X142443Y-810382D02*
X142286Y-810277D01*
Y-810067D01*
X142443Y-809962D01*
X142600Y-810067D01*
Y-810277D01*
X142443Y-810382D01*
G01X210093Y-779172D02*
Y-787172D01*
X214093D01*
G01X221893D02*
Y-781839D01*
G01Y-782772D02*
X221493Y-782239D01*
X220893Y-781972D01*
X220193Y-781839D01*
X219493Y-782105D01*
X218893Y-782639D01*
X218493Y-783439D01*
X218293Y-784505D01*
X218493Y-785572D01*
X218893Y-786372D01*
X219493Y-786905D01*
X220193Y-787172D01*
X220893Y-787039D01*
X221493Y-786639D01*
X221893Y-786106D01*
G01X225993Y-789572D02*
X226593Y-789839D01*
X227393Y-789572D01*
X227893Y-789039D01*
X228293Y-788372D01*
X228893Y-786239D01*
X230193Y-781839D01*
G01X226993D02*
X228893Y-786239D01*
G01X234593Y-783572D02*
X237793D01*
X237493Y-782639D01*
X236993Y-782105D01*
X236293Y-781839D01*
X235593Y-781972D01*
X234993Y-782372D01*
X234593Y-783305D01*
X234393Y-784106D01*
Y-784905D01*
X234593Y-785705D01*
X235093Y-786505D01*
X235693Y-787039D01*
X236393Y-787172D01*
X237093Y-786905D01*
X237793Y-786106D01*
G01X242693Y-787172D02*
Y-781839D01*
G01Y-782905D02*
X243193Y-782372D01*
X243693Y-781972D01*
X244393Y-781839D01*
X244893Y-781972D01*
X245493Y-782372D01*
G01X229193Y-829172D02*
X232993D01*
X229193Y-837172D01*
X232993D01*
G01X239093Y-831839D02*
Y-837172D01*
G01Y-829705D02*
X238893Y-829572D01*
Y-829305D01*
X239093Y-829172D01*
X239293Y-829305D01*
Y-829572D01*
X239093Y-829705D01*
G01X245793Y-834505D02*
X248393D01*
G01X253093Y-837172D02*
Y-829172D01*
X255493D01*
X256293Y-829572D01*
X256893Y-830505D01*
X257093Y-831572D01*
X256893Y-832639D01*
X256393Y-833439D01*
X255493Y-833839D01*
X253093D01*
G01X263093Y-831839D02*
Y-837172D01*
G01Y-829705D02*
X262893Y-829572D01*
Y-829305D01*
X263093Y-829172D01*
X263293Y-829305D01*
Y-829572D01*
X263093Y-829705D01*
G01X269393Y-837172D02*
Y-831839D01*
G01Y-833172D02*
X269793Y-832505D01*
X270393Y-831972D01*
X271193Y-831839D01*
X271893Y-831972D01*
X272493Y-832505D01*
X272793Y-833439D01*
Y-837172D01*
G01X277693Y-839172D02*
X278393Y-839705D01*
X279193Y-839839D01*
X279893Y-839705D01*
X280493Y-839039D01*
X280893Y-838105D01*
Y-831839D01*
G01Y-832905D02*
X280493Y-832372D01*
X279893Y-831972D01*
X279193Y-831839D01*
X278393Y-832105D01*
X277893Y-832639D01*
X277493Y-833572D01*
X277293Y-834505D01*
X277393Y-835305D01*
X277793Y-836239D01*
X278393Y-836905D01*
X279193Y-837172D01*
X279793Y-837039D01*
X280493Y-836505D01*
X280893Y-835972D01*
G01X244193Y-808172D02*
X246193D01*
Y-810572D01*
X245593Y-811372D01*
X244893Y-811905D01*
X243893Y-812172D01*
X242893Y-811905D01*
X242193Y-811372D01*
X241593Y-810572D01*
X241193Y-809639D01*
X240993Y-808572D01*
Y-807639D01*
X241193Y-806839D01*
X241593Y-805905D01*
X242193Y-805105D01*
X242793Y-804572D01*
X243593Y-804172D01*
X244293D01*
X245093Y-804439D01*
X245693Y-804972D01*
G01X249293Y-812172D02*
Y-804172D01*
X253893Y-812172D01*
Y-804172D01*
G01X257393Y-812172D02*
Y-804172D01*
X259393D01*
X260193Y-804572D01*
X260793Y-805105D01*
X261293Y-805905D01*
X261693Y-806839D01*
X261793Y-808172D01*
X261693Y-809505D01*
X261293Y-810439D01*
X260793Y-811239D01*
X260193Y-811772D01*
X259393Y-812172D01*
X257393D01*
G01X267593D02*
Y-804172D01*
X266393Y-805772D01*
G01Y-812172D02*
X268793D01*
G01X264793Y-787172D02*
Y-779172D01*
X261093Y-784905D01*
X266093D01*
G01X336693Y-830505D02*
X337293Y-829705D01*
X337993Y-829305D01*
X338793Y-829172D01*
X339793Y-829439D01*
X340493Y-830105D01*
X340693Y-830905D01*
X340593Y-831706D01*
X340193Y-832372D01*
X338193Y-833705D01*
X337293Y-834639D01*
X336693Y-835972D01*
X336493Y-837172D01*
X340693D01*
G01X346593Y-829172D02*
X345793Y-829439D01*
X345193Y-830105D01*
X344793Y-830905D01*
X344493Y-831972D01*
X344393Y-833172D01*
X344493Y-834372D01*
X344793Y-835439D01*
X345193Y-836239D01*
X345793Y-836905D01*
X346593Y-837172D01*
X347393Y-836905D01*
X347993Y-836239D01*
X348393Y-835439D01*
X348693Y-834372D01*
X348793Y-833172D01*
X348693Y-831972D01*
X348393Y-830905D01*
X347993Y-830105D01*
X347393Y-829439D01*
X346593Y-829172D01*
G01X352693Y-830505D02*
X353293Y-829705D01*
X353993Y-829305D01*
X354793Y-829172D01*
X355793Y-829439D01*
X356493Y-830105D01*
X356693Y-830905D01*
X356593Y-831706D01*
X356193Y-832372D01*
X354193Y-833705D01*
X353293Y-834639D01*
X352693Y-835972D01*
X352493Y-837172D01*
X356693D01*
G01X360693Y-830505D02*
X361293Y-829705D01*
X361993Y-829305D01*
X362793Y-829172D01*
X363793Y-829439D01*
X364493Y-830105D01*
X364693Y-830905D01*
X364593Y-831706D01*
X364193Y-832372D01*
X362193Y-833705D01*
X361293Y-834639D01*
X360693Y-835972D01*
X360493Y-837172D01*
X364693D01*
G01X368793Y-837439D02*
X372393Y-829172D01*
G01X378593Y-837172D02*
Y-829172D01*
X377393Y-830772D01*
G01Y-837172D02*
X379793D01*
G01X384693Y-830505D02*
X385293Y-829705D01*
X385993Y-829305D01*
X386793Y-829172D01*
X387793Y-829439D01*
X388493Y-830105D01*
X388693Y-830905D01*
X388593Y-831706D01*
X388193Y-832372D01*
X386193Y-833705D01*
X385293Y-834639D01*
X384693Y-835972D01*
X384493Y-837172D01*
X388693D01*
G01X392793Y-837439D02*
X396393Y-829172D01*
G01X402593D02*
X401793Y-829439D01*
X401193Y-830105D01*
X400793Y-830905D01*
X400493Y-831972D01*
X400393Y-833172D01*
X400493Y-834372D01*
X400793Y-835439D01*
X401193Y-836239D01*
X401793Y-836905D01*
X402593Y-837172D01*
X403393Y-836905D01*
X403993Y-836239D01*
X404393Y-835439D01*
X404693Y-834372D01*
X404793Y-833172D01*
X404693Y-831972D01*
X404393Y-830905D01*
X403993Y-830105D01*
X403393Y-829439D01*
X402593Y-829172D01*
G01X408693Y-830505D02*
X409293Y-829705D01*
X409993Y-829305D01*
X410793Y-829172D01*
X411793Y-829439D01*
X412493Y-830105D01*
X412693Y-830905D01*
X412593Y-831706D01*
X412193Y-832372D01*
X410193Y-833705D01*
X409293Y-834639D01*
X408693Y-835972D01*
X408493Y-837172D01*
X412693D01*
G01X336393Y-814672D02*
Y-806672D01*
X338393D01*
X339193Y-807072D01*
X339793Y-807605D01*
X340293Y-808405D01*
X340693Y-809339D01*
X340793Y-810672D01*
X340693Y-812005D01*
X340293Y-812939D01*
X339793Y-813739D01*
X339193Y-814272D01*
X338393Y-814672D01*
X336393D01*
G01X344093D02*
X346593Y-806672D01*
X349093Y-814672D01*
G01X348193Y-811872D02*
X344993D01*
G01X354593Y-806672D02*
X353793Y-806939D01*
X353193Y-807605D01*
X352793Y-808405D01*
X352493Y-809472D01*
X352393Y-810672D01*
X352493Y-811872D01*
X352793Y-812939D01*
X353193Y-813739D01*
X353793Y-814405D01*
X354593Y-814672D01*
X355393Y-814405D01*
X355993Y-813739D01*
X356393Y-812939D01*
X356693Y-811872D01*
X356793Y-810672D01*
X356693Y-809472D01*
X356393Y-808405D01*
X355993Y-807605D01*
X355393Y-806939D01*
X354593Y-806672D01*
G01X360693Y-814672D02*
Y-806672D01*
X364493D01*
G01X363093Y-810539D02*
X360693D01*
G01X370593Y-806672D02*
X369793Y-806939D01*
X369193Y-807605D01*
X368793Y-808405D01*
X368493Y-809472D01*
X368393Y-810672D01*
X368493Y-811872D01*
X368793Y-812939D01*
X369193Y-813739D01*
X369793Y-814405D01*
X370593Y-814672D01*
X371393Y-814405D01*
X371993Y-813739D01*
X372393Y-812939D01*
X372693Y-811872D01*
X372793Y-810672D01*
X372693Y-809472D01*
X372393Y-808405D01*
X371993Y-807605D01*
X371393Y-806939D01*
X370593Y-806672D01*
G01X378593D02*
Y-814672D01*
G01X376293Y-806672D02*
X380893D01*
G01X384593Y-814672D02*
Y-806672D01*
X386993D01*
X387793Y-807072D01*
X388393Y-808005D01*
X388593Y-809072D01*
X388393Y-810139D01*
X387893Y-810939D01*
X386993Y-811339D01*
X384593D01*
G01X395393Y-810405D02*
X395793Y-810005D01*
X396093Y-809339D01*
X396293Y-808405D01*
X396093Y-807605D01*
X395693Y-807072D01*
X394993Y-806672D01*
X392293D01*
Y-814672D01*
X395593D01*
X396293Y-814139D01*
X396693Y-813339D01*
X396893Y-812405D01*
X396693Y-811472D01*
X396093Y-810672D01*
X395393Y-810405D01*
X392293D01*
G01X400093Y-814672D02*
X402593Y-806672D01*
X405093Y-814672D01*
G01X404193Y-811872D02*
X400993D01*
G01X408693Y-814672D02*
Y-806672D01*
X412493D01*
G01X411093Y-810539D02*
X408693D01*
G01X418593Y-806672D02*
X417793Y-806939D01*
X417193Y-807605D01*
X416793Y-808405D01*
X416493Y-809472D01*
X416393Y-810672D01*
X416493Y-811872D01*
X416793Y-812939D01*
X417193Y-813739D01*
X417793Y-814405D01*
X418593Y-814672D01*
X419393Y-814405D01*
X419993Y-813739D01*
X420393Y-812939D01*
X420693Y-811872D01*
X420793Y-810672D01*
X420693Y-809472D01*
X420393Y-808405D01*
X419993Y-807605D01*
X419393Y-806939D01*
X418593Y-806672D01*
G01X356693Y-787172D02*
Y-779172D01*
X360493D01*
G01X359093Y-783039D02*
X356693D01*
G01X366593Y-779172D02*
X365793Y-779439D01*
X365193Y-780105D01*
X364793Y-780905D01*
X364493Y-781972D01*
X364393Y-783172D01*
X364493Y-784372D01*
X364793Y-785439D01*
X365193Y-786239D01*
X365793Y-786905D01*
X366593Y-787172D01*
X367393Y-786905D01*
X367993Y-786239D01*
X368393Y-785439D01*
X368693Y-784372D01*
X368793Y-783172D01*
X368693Y-781972D01*
X368393Y-780905D01*
X367993Y-780105D01*
X367393Y-779439D01*
X366593Y-779172D01*
G01X374593D02*
Y-787172D01*
G01X372293Y-779172D02*
X376893D01*
G01X379593Y-789839D02*
X385593D01*
G01X388593Y-787172D02*
Y-779172D01*
X390993D01*
X391793Y-779572D01*
X392393Y-780505D01*
X392593Y-781572D01*
X392393Y-782639D01*
X391893Y-783439D01*
X390993Y-783839D01*
X388593D01*
G01X396393Y-787172D02*
Y-779172D01*
X398393D01*
X399193Y-779572D01*
X399793Y-780105D01*
X400293Y-780905D01*
X400693Y-781839D01*
X400793Y-783172D01*
X400693Y-784505D01*
X400293Y-785439D01*
X399793Y-786239D01*
X399193Y-786772D01*
X398393Y-787172D01*
X396393D01*
G01X407393Y-782905D02*
X407793Y-782505D01*
X408093Y-781839D01*
X408293Y-780905D01*
X408093Y-780105D01*
X407693Y-779572D01*
X406993Y-779172D01*
X404293D01*
Y-787172D01*
X407593D01*
X408293Y-786639D01*
X408693Y-785839D01*
X408893Y-784905D01*
X408693Y-783972D01*
X408093Y-783172D01*
X407393Y-782905D01*
X404293D01*
G01X411593Y-789839D02*
X417593D01*
G01X424793Y-779839D02*
X424193Y-779439D01*
X423493Y-779172D01*
X422693D01*
X421793Y-779572D01*
X421093Y-780239D01*
X420593Y-781039D01*
X420193Y-782372D01*
X420093Y-783572D01*
X420293Y-784772D01*
X420593Y-785572D01*
X421193Y-786372D01*
X421893Y-786905D01*
X422593Y-787172D01*
X423293D01*
X423993Y-786905D01*
X424593Y-786505D01*
X425093Y-785972D01*
G01X430593Y-787172D02*
X429793Y-787039D01*
X429093Y-786505D01*
X428493Y-785705D01*
X428093Y-784772D01*
X427893Y-783705D01*
Y-782639D01*
X428093Y-781572D01*
X428493Y-780639D01*
X429093Y-779839D01*
X429793Y-779305D01*
X430593Y-779172D01*
X431393Y-779305D01*
X432093Y-779839D01*
X432693Y-780639D01*
X433093Y-781572D01*
X433293Y-782639D01*
Y-783705D01*
X433093Y-784772D01*
X432693Y-785705D01*
X432093Y-786505D01*
X431393Y-787039D01*
X430593Y-787172D01*
G01X436293D02*
Y-779172D01*
X440893Y-787172D01*
Y-779172D01*
G01X444093D02*
X446593Y-787172D01*
X449093Y-779172D01*
G01X456593Y-787172D02*
X452593D01*
Y-779172D01*
X456593D01*
G01X454993Y-783039D02*
X452593D01*
G01X460593Y-787172D02*
Y-779172D01*
X463093D01*
X463893Y-779572D01*
X464393Y-780105D01*
X464593Y-781172D01*
X464393Y-782239D01*
X463793Y-782905D01*
X463093Y-783305D01*
X460593D01*
G01X463093D02*
X464593Y-787172D01*
G01X470593Y-779172D02*
Y-787172D01*
G01X468293Y-779172D02*
X472893D01*
G01X480593Y-787172D02*
X476593D01*
Y-779172D01*
X480593D01*
G01X478993Y-783039D02*
X476593D01*
G01X484593Y-787172D02*
Y-779172D01*
X487093D01*
X487893Y-779572D01*
X488393Y-780105D01*
X488593Y-781172D01*
X488393Y-782239D01*
X487793Y-782905D01*
X487093Y-783305D01*
X484593D01*
G01X487093D02*
X488593Y-787172D01*
G01X425093Y-840172D02*
Y-832172D01*
X423893Y-833772D01*
G01Y-840172D02*
X426293D01*
G01X431193Y-836839D02*
X431893Y-835905D01*
X432493Y-835372D01*
X433293Y-835105D01*
X433993Y-835372D01*
X434493Y-835905D01*
X434893Y-836705D01*
X434993Y-837639D01*
X434893Y-838439D01*
X434493Y-839239D01*
X433893Y-839905D01*
X433193Y-840172D01*
X432393Y-839905D01*
X431693Y-839106D01*
X431293Y-837905D01*
X431193Y-836572D01*
X431393Y-834839D01*
X431693Y-833905D01*
X432193Y-832972D01*
X432893Y-832305D01*
X433593Y-832172D01*
X434293Y-832439D01*
X434793Y-833105D01*
G01X441093Y-840439D02*
X440893Y-840305D01*
Y-840039D01*
X441093Y-839905D01*
X441293Y-840039D01*
Y-840305D01*
X441093Y-840439D01*
G01X447193Y-836839D02*
X447893Y-835905D01*
X448493Y-835372D01*
X449293Y-835105D01*
X449993Y-835372D01*
X450493Y-835905D01*
X450893Y-836705D01*
X450993Y-837639D01*
X450893Y-838439D01*
X450493Y-839239D01*
X449893Y-839905D01*
X449193Y-840172D01*
X448393Y-839905D01*
X447693Y-839106D01*
X447293Y-837905D01*
X447193Y-836572D01*
X447393Y-834839D01*
X447693Y-833905D01*
X448193Y-832972D01*
X448893Y-832305D01*
X449593Y-832172D01*
X450293Y-832439D01*
X450793Y-833105D01*
G01X470093Y-840172D02*
Y-832172D01*
X468893Y-833772D01*
G01Y-840172D02*
X471293D01*
G01X477893D02*
X478093Y-838439D01*
X478393Y-836972D01*
X478793Y-835639D01*
X479293Y-834172D01*
X480093Y-832172D01*
X476093D01*
G01X486093Y-840439D02*
X485893Y-840305D01*
Y-840039D01*
X486093Y-839905D01*
X486293Y-840039D01*
Y-840305D01*
X486093Y-840439D01*
G01X492193Y-833505D02*
X492793Y-832705D01*
X493493Y-832305D01*
X494293Y-832172D01*
X495293Y-832439D01*
X495993Y-833105D01*
X496193Y-833905D01*
X496093Y-834706D01*
X495693Y-835372D01*
X493693Y-836705D01*
X492793Y-837639D01*
X492193Y-838972D01*
X491993Y-840172D01*
X496193D01*
G01X490193Y-815172D02*
Y-807172D01*
X493993D01*
G01X492593Y-811039D02*
X490193D01*
G54D49*
G01X808570Y269708D02*
X808500Y269778D01*
Y272925D01*
G01X850500Y360075D02*
Y362921D01*
G01X927000Y361075D02*
Y363714D01*
M02*
